FILE_TYPE = MACRO_DRAWING;
SET COLOR_WIRE YELLOW;
SET COLOR_PROP ORANGE;
SET COLOR_DOT WHITE;
SET COLOR_ARC YELLOW;
SET COLOR_BODY GREEN;
SET COLOR_NOTE PURPLE;
SET PROP_DISPLAY VALUE;
SET PAGE_NUMBER P478;
FORCEADD UNIVERSAL_GND..1
(-9500 825);
FORCEPROP 3 LASTPIN (-9500 875) SIG_NAME GND\g
J 0
(-9490 885);
DISPLAY 0.659574 (-9490 885);
PAINT MONO (-9490 885);
DISPLAY INVISIBLE (-9490 885);
FORCEPROP 1 LAST PATH I1
J 0
(-9425 825);
DISPLAY 0.872340 (-9425 825);
PAINT AQUA (-9425 825);
DISPLAY INVISIBLE (-9425 825);
FORCEPROP 1 LAST HDL_POWER GND
J 1
(-9475 750);
DISPLAY 0.872340 (-9475 750);
PAINT GREEN (-9475 750);
DISPLAY INVISIBLE (-9475 750);
FORCEPROP 2 LAST CDS_LIB pure_quanta_power
J 0
(-9500 825);
DISPLAY INVISIBLE (-9500 825);
FORCEADD Q_CAP..1
(-8750 1875);
FORCEPROP 1 LAST LOCATION PC6645
J 0
(-8700 1975);
DISPLAY 0.978723 (-8700 1975);
FORCEPROP 0 LAST $SEC 1
J 0
(-8700 2025);
DISPLAY 0.680851 (-8700 2025);
PAINT MONO (-8700 2025);
DISPLAY INVISIBLE (-8700 2025);
FORCEPROP 0 LAST CDS_SEC 1
J 0
(-8700 2025);
DISPLAY 0.680851 (-8700 2025);
DISPLAY INVISIBLE (-8700 2025);
FORCEPROP 1 LASTPIN (-8750 1975) $PN 1
J 0
(-8740 1955);
DISPLAY 0.787234 (-8740 1955);
PAINT MONO (-8740 1955);
FORCEPROP 1 LASTPIN (-8750 1775) $PN 2
J 0
(-8740 1755);
DISPLAY 0.787234 (-8740 1755);
PAINT MONO (-8740 1755);
FORCEPROP 1 LAST MATERIAL X6S
J 0
(-8700 1825);
DISPLAY 0.617021 (-8700 1825);
FORCEPROP 1 LAST PACK_TYPE C0402
J 0
(-8700 1725);
DISPLAY 0.617021 (-8700 1725);
FORCEPROP 1 LAST VOLTAGE 10V
J 0
(-8700 1875);
DISPLAY 0.617021 (-8700 1875);
FORCEPROP 1 LAST VALUE 2.2UF
J 0
(-8700 1925);
DISPLAY 0.617021 (-8700 1925);
FORCEPROP 1 LAST PATH I10
J 0
(-8700 2025);
DISPLAY 0.978723 (-8700 2025);
PAINT WHITE (-8700 2025);
DISPLAY INVISIBLE (-8700 2025);
FORCEPROP 1 LAST PART_NUMBER CH5222KEB01
J 0
(-8700 1775);
DISPLAY 0.617021 (-8700 1775);
DISPLAY INVISIBLE (-8700 1775);
FORCEPROP 2 LAST CDS_LIB pure_quanta
J 0
(-8750 1875);
DISPLAY INVISIBLE (-8750 1875);
FORCEPROP 1 LAST TOLERANCE 10%
J 0
(-8700 1825);
DISPLAY 0.978723 (-8700 1825);
PAINT SKYBLUE (-8700 1825);
DISPLAY INVISIBLE (-8700 1825);
FORCEPROP 2 LAST BOM_COST VR_DIMM 
J 0
(-8700 2025);
DISPLAY 0.680851 (-8700 2025);
DISPLAY INVISIBLE (-8700 2025);
FORCEADD Q_CAP..1
(-2775 5100);
FORCEPROP 1 LAST LOCATION PC6819
J 0
(-2725 5200);
DISPLAY 0.978723 (-2725 5200);
FORCEPROP 0 LAST $SEC 1
J 0
(-2725 5250);
DISPLAY 0.680851 (-2725 5250);
PAINT MONO (-2725 5250);
DISPLAY INVISIBLE (-2725 5250);
FORCEPROP 0 LAST CDS_SEC 1
J 0
(-2725 5250);
DISPLAY 0.680851 (-2725 5250);
DISPLAY INVISIBLE (-2725 5250);
FORCEPROP 1 LASTPIN (-2775 5200) $PN 1
J 0
(-2765 5180);
DISPLAY 0.787234 (-2765 5180);
PAINT MONO (-2765 5180);
FORCEPROP 1 LASTPIN (-2775 5000) $PN 2
J 0
(-2765 4980);
DISPLAY 0.787234 (-2765 4980);
PAINT MONO (-2765 4980);
FORCEPROP 1 LAST VOLTAGE 16V
J 0
(-2725 5100);
DISPLAY 0.510638 (-2725 5100);
FORCEPROP 1 LAST PACK_TYPE C0805
J 0
(-2725 4900);
DISPLAY 0.510638 (-2725 4900);
FORCEPROP 1 LAST MATERIAL X6S
J 0
(-2725 5000);
DISPLAY 0.510638 (-2725 5000);
FORCEPROP 1 LAST TOLERANCE 20%
J 0
(-2725 5050);
DISPLAY 0.510638 (-2725 5050);
FORCEPROP 1 LAST VALUE 22UF
J 0
(-2725 5150);
DISPLAY 0.510638 (-2725 5150);
FORCEPROP 1 LAST PATH I100
J 0
(-2725 5250);
DISPLAY 0.978723 (-2725 5250);
PAINT WHITE (-2725 5250);
DISPLAY INVISIBLE (-2725 5250);
FORCEPROP 1 LAST PART_NUMBER CH6223MEA01
J 0
(-2725 4950);
DISPLAY 0.510638 (-2725 4950);
DISPLAY INVISIBLE (-2725 4950);
FORCEPROP 2 LAST CDS_LIB pure_quanta
J 0
(-2775 5100);
DISPLAY INVISIBLE (-2775 5100);
FORCEADD UNIVERSAL_GND..1
(-2375 4850);
FORCEPROP 3 LASTPIN (-2375 4900) SIG_NAME GND\g
J 0
(-2365 4910);
DISPLAY 0.659574 (-2365 4910);
PAINT MONO (-2365 4910);
DISPLAY INVISIBLE (-2365 4910);
FORCEPROP 1 LAST PATH I101
J 0
(-2300 4850);
DISPLAY 0.872340 (-2300 4850);
PAINT AQUA (-2300 4850);
DISPLAY INVISIBLE (-2300 4850);
FORCEPROP 1 LAST HDL_POWER GND
J 1
(-2350 4775);
DISPLAY 0.872340 (-2350 4775);
PAINT GREEN (-2350 4775);
DISPLAY INVISIBLE (-2350 4775);
FORCEPROP 2 LAST CDS_LIB pure_quanta_power
J 0
(-2375 4850);
DISPLAY INVISIBLE (-2375 4850);
FORCEADD Q_CAPP..1
(-2375 5125);
FORCEPROP 1 LAST LOCATION PC6619
J 0
(-2325 5225);
DISPLAY 0.787234 (-2325 5225);
FORCEPROP 0 LAST $SEC 1
J 0
(-2325 5275);
DISPLAY 0.680851 (-2325 5275);
PAINT MONO (-2325 5275);
DISPLAY INVISIBLE (-2325 5275);
FORCEPROP 0 LAST CDS_SEC 1
J 0
(-2325 5275);
DISPLAY 0.680851 (-2325 5275);
DISPLAY INVISIBLE (-2325 5275);
FORCEPROP 1 LASTPIN (-2375 5225) $PN 1
J 0
(-2365 5210);
DISPLAY 0.787234 (-2365 5210);
PAINT MONO (-2365 5210);
FORCEPROP 1 LASTPIN (-2375 5025) $PN 2
J 0
(-2365 5010);
DISPLAY 0.787234 (-2365 5010);
PAINT MONO (-2365 5010);
FORCEPROP 1 LAST PACK_TYPE SMLF
J 0
(-2325 4975);
DISPLAY 0.510638 (-2325 4975);
FORCEPROP 1 LAST MATERIAL OSCON
J 0
(-2325 5025);
DISPLAY 0.510638 (-2325 5025);
FORCEPROP 1 LAST VOLTAGE 16V
J 0
(-2325 5075);
DISPLAY 0.510638 (-2325 5075);
FORCEPROP 1 LAST VALUE 100UF
J 0
(-2325 5175);
DISPLAY 0.510638 (-2325 5175);
FORCEPROP 1 LAST TOLERANCE 20%
J 0
(-2325 5125);
DISPLAY 0.510638 (-2325 5125);
FORCEPROP 1 LAST PATH I102
J 0
(-2325 5275);
DISPLAY 0.978723 (-2325 5275);
DISPLAY INVISIBLE (-2325 5275);
FORCEPROP 1 LAST PART_NUMBER CC71003MZ30
J 0
(-2325 4925);
DISPLAY 0.510638 (-2325 4925);
DISPLAY INVISIBLE (-2325 4925);
FORCEPROP 2 LAST CDS_LIB pure_quanta
J 0
(-2375 5125);
DISPLAY INVISIBLE (-2375 5125);
FORCEADD VCC15..1
(-2425 5550);
FORCEPROP 3 LASTPIN (-2425 5500) SIG_NAME SW_P12V_AUX_P0V9_RETIMER_CPU1_FLT\g
J 0
(-2415 5510);
DISPLAY 0.659574 (-2415 5510);
PAINT MONO (-2415 5510);
DISPLAY INVISIBLE (-2415 5510);
FORCEPROP 1 LAST HDL_POWER SW_P12V_AUX_P0V9_RETIMER_CPU1_FLT
J 1
(-2525 5625);
DISPLAY 0.617021 (-2525 5625);
PAINT GREEN (-2525 5625);
FORCEPROP 1 LAST PATH I103
J 0
(-2375 5575);
DISPLAY 0.872340 (-2375 5575);
PAINT AQUA (-2375 5575);
DISPLAY INVISIBLE (-2375 5575);
FORCEPROP 2 LAST CDS_LIB pure_quanta_power
J 0
(-2425 5550);
DISPLAY INVISIBLE (-2425 5550);
FORCEPROP 2 LAST BOM_COST VR_DIMM 
J 0
(-2525 5675);
DISPLAY 0.680851 (-2525 5675);
DISPLAY INVISIBLE (-2525 5675);
FORCEADD Q_INDUCTOR..1
(-1825 5350);
FORCEPROP 1 LAST LOCATION PL6510
J 0
(-1950 5510);
DISPLAY 0.723404 (-1950 5510);
PAINT GREEN (-1950 5510);
FORCEPROP 0 LAST $SEC 1
J 0
(-1950 5650);
DISPLAY 0.680851 (-1950 5650);
PAINT MONO (-1950 5650);
DISPLAY INVISIBLE (-1950 5650);
FORCEPROP 0 LAST CDS_SEC 1
J 0
(-1950 5650);
DISPLAY 0.680851 (-1950 5650);
DISPLAY INVISIBLE (-1950 5650);
FORCEPROP 0 LASTPIN (-1925 5325) $PN 1
J 2
(-1935 5335);
DISPLAY 0.680851 (-1935 5335);
PAINT MONO (-1935 5335);
FORCEPROP 0 LASTPIN (-1725 5325) $PN 2
J 0
(-1715 5335);
DISPLAY 0.680851 (-1715 5335);
PAINT MONO (-1715 5335);
FORCEPROP 1 LAST MATERIAL IND
J 0
(-1950 5405);
DISPLAY 0.723404 (-1950 5405);
PAINT GREEN (-1950 5405);
FORCEPROP 2 LAST PACK_TYPE SMLF
J 0
(-1950 5550);
DISPLAY 1.021277 (-1950 5550);
FORCEPROP 2 LAST VALUE 100NH/16A
J 0
(-1950 5600);
DISPLAY 1.021277 (-1950 5600);
FORCEPROP 1 LAST PATH I104
J 0
(-1750 5405);
DISPLAY 0.723404 (-1750 5405);
PAINT GREEN (-1750 5405);
DISPLAY INVISIBLE (-1750 5405);
FORCEPROP 1 LAST PART_NUMBER CV+10G0MZ04
J 0
(-1950 5460);
DISPLAY 0.723404 (-1950 5460);
PAINT GREEN (-1950 5460);
DISPLAY INVISIBLE (-1950 5460);
FORCEPROP 2 LAST CDS_LIB pure_quanta
J 0
(-1825 5350);
DISPLAY INVISIBLE (-1825 5350);
FORCEPROP 1 LAST NEEDS_NO_SIZE TRUE
J 0
(-1825 5350);
DISPLAY 0.468085 (-1825 5350);
PAINT GREEN (-1825 5350);
DISPLAY INVISIBLE (-1825 5350);
FORCEADD UNIVERSAL_POWER..1
(-950 5575);
FORCEPROP 3 LASTPIN (-950 5525) SIG_NAME P12V_AUX\g
J 0
(-940 5535);
DISPLAY 0.659574 (-940 5535);
PAINT MONO (-940 5535);
DISPLAY INVISIBLE (-940 5535);
FORCEPROP 1 LAST HDL_POWER P12V_AUX
J 1
(-950 5625);
DISPLAY 0.617021 (-950 5625);
PAINT GREEN (-950 5625);
FORCEPROP 1 LAST PATH I105
J 0
(-900 5600);
DISPLAY 0.872340 (-900 5600);
PAINT AQUA (-900 5600);
DISPLAY INVISIBLE (-900 5600);
FORCEPROP 2 LAST BOM_COST VR_DIMM 
J 0
(-950 5675);
DISPLAY 0.617021 (-950 5675);
PAINT PURPLE (-950 5675);
DISPLAY INVISIBLE (-950 5675);
FORCEPROP 2 LAST CDS_LIB pure_quanta_power
J 0
(-950 5575);
DISPLAY INVISIBLE (-950 5575);
FORCEADD Q_RES..2
(-5425 3625);
FORCEPROP 1 LAST LOCATION PR6624
J 0
(-5380 3750);
DISPLAY 0.617021 (-5380 3750);
PAINT SKYBLUE (-5380 3750);
FORCEPROP 0 LAST $SEC 1
J 0
(-5375 3800);
DISPLAY 0.680851 (-5375 3800);
PAINT MONO (-5375 3800);
DISPLAY INVISIBLE (-5375 3800);
FORCEPROP 0 LAST CDS_SEC 1
J 0
(-5375 3800);
DISPLAY 0.680851 (-5375 3800);
DISPLAY INVISIBLE (-5375 3800);
FORCEPROP 1 LASTPIN (-5425 3725) $PN 1
J 0
(-5420 3687);
DISPLAY 0.787234 (-5420 3687);
PAINT MONO (-5420 3687);
FORCEPROP 1 LASTPIN (-5425 3525) $PN 2
J 0
(-5420 3535);
DISPLAY 0.787234 (-5420 3535);
PAINT MONO (-5420 3535);
FORCEPROP 1 LAST VALUE 1.5
J 0
(-5380 3700);
DISPLAY 0.489362 (-5380 3700);
PAINT SKYBLUE (-5380 3700);
FORCEPROP 1 LAST PACK_TYPE 0402LF
J 0
(-5385 3450);
DISPLAY 0.489362 (-5385 3450);
PAINT SKYBLUE (-5385 3450);
FORCEPROP 1 LAST TOLERANCE 1%
J 0
(-5380 3650);
DISPLAY 0.489362 (-5380 3650);
PAINT SKYBLUE (-5380 3650);
FORCEPROP 1 LAST WATTAGE 1/8W
J 0
(-5385 3600);
DISPLAY 0.489362 (-5385 3600);
PAINT SKYBLUE (-5385 3600);
FORCEPROP 1 LAST MATERIAL EMPTY
J 0
(-5385 3550);
DISPLAY 0.489362 (-5385 3550);
PAINT RED (-5385 3550);
FORCEPROP 1 LAST PATH I106
J 0
(-5375 3800);
DISPLAY 0.978723 (-5375 3800);
PAINT WHITE (-5375 3800);
DISPLAY INVISIBLE (-5375 3800);
FORCEPROP 1 LAST PART_NUMBER CS-1504FB00
J 0
(-5385 3500);
DISPLAY 0.489362 (-5385 3500);
PAINT SKYBLUE (-5385 3500);
DISPLAY INVISIBLE (-5385 3500);
FORCEPROP 2 LAST CDS_LIB pure_quanta
J 0
(-5425 3625);
DISPLAY INVISIBLE (-5425 3625);
FORCEADD UNIVERSAL_GND..1
(-5425 3400);
FORCEPROP 3 LASTPIN (-5425 3450) SIG_NAME GND\g
J 0
(-5415 3460);
DISPLAY 0.659574 (-5415 3460);
PAINT MONO (-5415 3460);
DISPLAY INVISIBLE (-5415 3460);
FORCEPROP 1 LAST PATH I107
J 0
(-5350 3400);
DISPLAY 0.872340 (-5350 3400);
PAINT AQUA (-5350 3400);
DISPLAY INVISIBLE (-5350 3400);
FORCEPROP 1 LAST HDL_POWER GND
J 1
(-5400 3325);
DISPLAY 0.872340 (-5400 3325);
PAINT GREEN (-5400 3325);
DISPLAY INVISIBLE (-5400 3325);
FORCEPROP 2 LAST CDS_LIB pure_quanta_power
J 0
(-5425 3400);
DISPLAY INVISIBLE (-5425 3400);
FORCEADD Q_CAP..1
(-5425 4150);
FORCEPROP 1 LAST LOCATION PC6622
J 0
(-5375 4250);
DISPLAY 0.617021 (-5375 4250);
PAINT SKYBLUE (-5375 4250);
FORCEPROP 0 LAST $SEC 1
J 0
(-5375 4300);
DISPLAY 0.680851 (-5375 4300);
PAINT MONO (-5375 4300);
DISPLAY INVISIBLE (-5375 4300);
FORCEPROP 0 LAST CDS_SEC 1
J 0
(-5375 4300);
DISPLAY 0.680851 (-5375 4300);
DISPLAY INVISIBLE (-5375 4300);
FORCEPROP 1 LASTPIN (-5425 4250) $PN 1
J 0
(-5415 4230);
DISPLAY 0.787234 (-5415 4230);
PAINT MONO (-5415 4230);
FORCEPROP 1 LASTPIN (-5425 4050) $PN 2
J 0
(-5415 4030);
DISPLAY 0.787234 (-5415 4030);
PAINT MONO (-5415 4030);
FORCEPROP 1 LAST TOLERANCE 10%
J 0
(-5375 4100);
DISPLAY 0.489362 (-5375 4100);
PAINT SKYBLUE (-5375 4100);
FORCEPROP 1 LAST MATERIAL EMPTY
J 0
(-5375 4050);
DISPLAY 0.489362 (-5375 4050);
PAINT RED (-5375 4050);
FORCEPROP 1 LAST PACK_TYPE C0402
J 0
(-5375 3950);
DISPLAY 0.489362 (-5375 3950);
PAINT SKYBLUE (-5375 3950);
FORCEPROP 1 LAST VALUE 560PF
J 0
(-5375 4200);
DISPLAY 0.489362 (-5375 4200);
PAINT SKYBLUE (-5375 4200);
FORCEPROP 1 LAST VOLTAGE 50V
J 0
(-5375 4150);
DISPLAY 0.489362 (-5375 4150);
PAINT SKYBLUE (-5375 4150);
FORCEPROP 1 LAST PATH I108
J 0
(-5375 4300);
DISPLAY 0.978723 (-5375 4300);
PAINT WHITE (-5375 4300);
DISPLAY INVISIBLE (-5375 4300);
FORCEPROP 1 LAST PART_NUMBER CH1566K1B09
J 0
(-5375 4000);
DISPLAY 0.489362 (-5375 4000);
PAINT SKYBLUE (-5375 4000);
DISPLAY INVISIBLE (-5375 4000);
FORCEPROP 2 LAST CDS_LIB pure_quanta
J 0
(-5425 4150);
DISPLAY INVISIBLE (-5425 4150);
FORCEADD Q_CAP..1
(-5400 1250);
FORCEPROP 1 LAST LOCATION PC6641
J 0
(-5350 1350);
DISPLAY 0.617021 (-5350 1350);
PAINT SKYBLUE (-5350 1350);
FORCEPROP 0 LAST $SEC 1
J 0
(-5350 1400);
DISPLAY 0.680851 (-5350 1400);
PAINT MONO (-5350 1400);
DISPLAY INVISIBLE (-5350 1400);
FORCEPROP 0 LAST CDS_SEC 1
J 0
(-5350 1400);
DISPLAY 0.680851 (-5350 1400);
DISPLAY INVISIBLE (-5350 1400);
FORCEPROP 1 LASTPIN (-5400 1350) $PN 1
J 0
(-5390 1330);
DISPLAY 0.787234 (-5390 1330);
PAINT MONO (-5390 1330);
FORCEPROP 1 LASTPIN (-5400 1150) $PN 2
J 0
(-5390 1130);
DISPLAY 0.787234 (-5390 1130);
PAINT MONO (-5390 1130);
FORCEPROP 1 LAST VALUE 560PF
J 0
(-5350 1300);
DISPLAY 0.489362 (-5350 1300);
PAINT SKYBLUE (-5350 1300);
FORCEPROP 1 LAST VOLTAGE 50V
J 0
(-5350 1250);
DISPLAY 0.489362 (-5350 1250);
PAINT SKYBLUE (-5350 1250);
FORCEPROP 1 LAST TOLERANCE 10%
J 0
(-5350 1200);
DISPLAY 0.489362 (-5350 1200);
PAINT SKYBLUE (-5350 1200);
FORCEPROP 1 LAST MATERIAL EMPTY
J 0
(-5350 1150);
DISPLAY 0.489362 (-5350 1150);
PAINT RED (-5350 1150);
FORCEPROP 1 LAST PACK_TYPE C0402
J 0
(-5350 1050);
DISPLAY 0.489362 (-5350 1050);
PAINT SKYBLUE (-5350 1050);
FORCEPROP 1 LAST PATH I109
J 0
(-5350 1400);
DISPLAY 0.978723 (-5350 1400);
PAINT WHITE (-5350 1400);
DISPLAY INVISIBLE (-5350 1400);
FORCEPROP 1 LAST PART_NUMBER CH1566K1B09
J 0
(-5350 1100);
DISPLAY 0.489362 (-5350 1100);
PAINT SKYBLUE (-5350 1100);
DISPLAY INVISIBLE (-5350 1100);
FORCEPROP 2 LAST CDS_LIB pure_quanta
J 0
(-5400 1250);
DISPLAY INVISIBLE (-5400 1250);
FORCEADD Q_RES..2
(-8750 2400);
FORCEPROP 1 LAST LOCATION PR6627
J 0
(-8705 2525);
DISPLAY 0.723404 (-8705 2525);
FORCEPROP 0 LAST $SEC 1
J 0
(-8700 2575);
DISPLAY 0.680851 (-8700 2575);
PAINT MONO (-8700 2575);
DISPLAY INVISIBLE (-8700 2575);
FORCEPROP 0 LAST CDS_SEC 1
J 0
(-8700 2575);
DISPLAY 0.680851 (-8700 2575);
DISPLAY INVISIBLE (-8700 2575);
FORCEPROP 1 LASTPIN (-8750 2500) $PN 1
J 0
(-8745 2462);
DISPLAY 0.787234 (-8745 2462);
PAINT MONO (-8745 2462);
FORCEPROP 1 LASTPIN (-8750 2300) $PN 2
J 0
(-8745 2310);
DISPLAY 0.787234 (-8745 2310);
PAINT MONO (-8745 2310);
FORCEPROP 1 LAST WATTAGE 1/16W
J 0
(-8710 2375);
DISPLAY 0.617021 (-8710 2375);
FORCEPROP 1 LAST MATERIAL CHIP
J 0
(-8710 2325);
DISPLAY 0.617021 (-8710 2325);
FORCEPROP 1 LAST PACK_TYPE 0402LF
J 0
(-8710 2225);
DISPLAY 0.617021 (-8710 2225);
FORCEPROP 1 LAST TOLERANCE 5%
J 0
(-8705 2425);
DISPLAY 0.617021 (-8705 2425);
FORCEPROP 1 LAST VALUE 2.2
J 0
(-8705 2475);
DISPLAY 0.617021 (-8705 2475);
FORCEPROP 1 LAST PATH I11
J 0
(-8700 2575);
DISPLAY 0.978723 (-8700 2575);
PAINT WHITE (-8700 2575);
DISPLAY INVISIBLE (-8700 2575);
FORCEPROP 1 LAST PART_NUMBER TMP_QCS-2202JB25
J 0
(-8725 2275);
DISPLAY 0.617021 (-8725 2275);
DISPLAY INVISIBLE (-8725 2275);
FORCEPROP 2 LAST CDS_LIB pure_quanta
J 0
(-8750 2400);
DISPLAY INVISIBLE (-8750 2400);
FORCEPROP 2 LAST BOM_COST VR_DIMM 
J 0
(-8700 2575);
DISPLAY 0.680851 (-8700 2575);
DISPLAY INVISIBLE (-8700 2575);
FORCEADD Q_RES..2
(-5400 725);
FORCEPROP 1 LAST LOCATION PR6630
J 0
(-5355 850);
DISPLAY 0.617021 (-5355 850);
PAINT SKYBLUE (-5355 850);
FORCEPROP 0 LAST $SEC 1
J 0
(-5350 900);
DISPLAY 0.680851 (-5350 900);
PAINT MONO (-5350 900);
DISPLAY INVISIBLE (-5350 900);
FORCEPROP 0 LAST CDS_SEC 1
J 0
(-5350 900);
DISPLAY 0.680851 (-5350 900);
DISPLAY INVISIBLE (-5350 900);
FORCEPROP 1 LASTPIN (-5400 825) $PN 1
J 0
(-5395 787);
DISPLAY 0.787234 (-5395 787);
PAINT MONO (-5395 787);
FORCEPROP 1 LASTPIN (-5400 625) $PN 2
J 0
(-5395 635);
DISPLAY 0.787234 (-5395 635);
PAINT MONO (-5395 635);
FORCEPROP 1 LAST MATERIAL EMPTY
J 0
(-5360 650);
DISPLAY 0.489362 (-5360 650);
PAINT RED (-5360 650);
FORCEPROP 1 LAST PACK_TYPE 0402LF
J 0
(-5360 550);
DISPLAY 0.489362 (-5360 550);
PAINT SKYBLUE (-5360 550);
FORCEPROP 1 LAST TOLERANCE 1%
J 0
(-5355 750);
DISPLAY 0.489362 (-5355 750);
PAINT SKYBLUE (-5355 750);
FORCEPROP 1 LAST WATTAGE 1/8W
J 0
(-5360 700);
DISPLAY 0.489362 (-5360 700);
PAINT SKYBLUE (-5360 700);
FORCEPROP 1 LAST VALUE 1.5
J 0
(-5355 800);
DISPLAY 0.489362 (-5355 800);
PAINT SKYBLUE (-5355 800);
FORCEPROP 1 LAST PATH I110
J 0
(-5350 900);
DISPLAY 0.978723 (-5350 900);
PAINT WHITE (-5350 900);
DISPLAY INVISIBLE (-5350 900);
FORCEPROP 1 LAST PART_NUMBER CS-1504FB00
J 0
(-5360 600);
DISPLAY 0.489362 (-5360 600);
PAINT SKYBLUE (-5360 600);
DISPLAY INVISIBLE (-5360 600);
FORCEPROP 2 LAST CDS_LIB pure_quanta
J 0
(-5400 725);
DISPLAY INVISIBLE (-5400 725);
FORCEADD UNIVERSAL_GND..1
(-5400 500);
FORCEPROP 3 LASTPIN (-5400 550) SIG_NAME GND\g
J 0
(-5390 560);
DISPLAY 0.659574 (-5390 560);
PAINT MONO (-5390 560);
DISPLAY INVISIBLE (-5390 560);
FORCEPROP 1 LAST PATH I111
J 0
(-5325 500);
DISPLAY 0.872340 (-5325 500);
PAINT AQUA (-5325 500);
DISPLAY INVISIBLE (-5325 500);
FORCEPROP 1 LAST HDL_POWER GND
J 1
(-5375 425);
DISPLAY 0.872340 (-5375 425);
PAINT GREEN (-5375 425);
DISPLAY INVISIBLE (-5375 425);
FORCEPROP 2 LAST CDS_LIB pure_quanta_power
J 0
(-5400 500);
DISPLAY INVISIBLE (-5400 500);
FORCEADD UNIVERSAL_POWER..1
(-8350 5675);
FORCEPROP 3 LASTPIN (-8350 5625) SIG_NAME P0V9_RETIMER_CPU1_PVCC\g
J 0
(-8340 5635);
DISPLAY 0.659574 (-8340 5635);
PAINT MONO (-8340 5635);
DISPLAY INVISIBLE (-8340 5635);
FORCEPROP 1 LAST HDL_POWER P0V9_RETIMER_CPU1_PVCC
J 1
(-8350 5725);
DISPLAY 0.872340 (-8350 5725);
PAINT GREEN (-8350 5725);
FORCEPROP 1 LAST PATH I112
J 0
(-8300 5700);
DISPLAY 0.872340 (-8300 5700);
PAINT AQUA (-8300 5700);
DISPLAY INVISIBLE (-8300 5700);
FORCEPROP 2 LAST CDS_LIB pure_quanta_power
J 0
(-8350 5675);
DISPLAY INVISIBLE (-8350 5675);
FORCEADD UNIVERSAL_GND..1
(-950 4800);
FORCEPROP 3 LASTPIN (-950 4850) SIG_NAME GND\g
J 0
(-940 4860);
DISPLAY 0.659574 (-940 4860);
PAINT MONO (-940 4860);
DISPLAY INVISIBLE (-940 4860);
FORCEPROP 1 LAST PATH I113
J 0
(-875 4800);
DISPLAY 0.872340 (-875 4800);
PAINT AQUA (-875 4800);
DISPLAY INVISIBLE (-875 4800);
FORCEPROP 1 LAST HDL_POWER GND
J 1
(-925 4725);
DISPLAY 0.872340 (-925 4725);
PAINT GREEN (-925 4725);
DISPLAY INVISIBLE (-925 4725);
FORCEPROP 2 LAST CDS_LIB pure_quanta_power
J 0
(-950 4800);
DISPLAY INVISIBLE (-950 4800);
FORCEADD Q_CAP..1
(-950 5125);
FORCEPROP 1 LAST LOCATION PC6620
J 0
(-900 5225);
DISPLAY 0.489362 (-900 5225);
PAINT SKYBLUE (-900 5225);
FORCEPROP 0 LAST $SEC 1
J 0
(-900 5250);
DISPLAY 0.680851 (-900 5250);
PAINT MONO (-900 5250);
DISPLAY INVISIBLE (-900 5250);
FORCEPROP 0 LAST CDS_SEC 1
J 0
(-900 5250);
DISPLAY 0.680851 (-900 5250);
DISPLAY INVISIBLE (-900 5250);
FORCEPROP 1 LASTPIN (-950 5225) $PN 1
J 0
(-940 5205);
DISPLAY 0.787234 (-940 5205);
PAINT MONO (-940 5205);
FORCEPROP 1 LASTPIN (-950 5025) $PN 2
J 0
(-940 5005);
DISPLAY 0.787234 (-940 5005);
PAINT MONO (-940 5005);
FORCEPROP 1 LAST VOLTAGE 25V
J 0
(-900 5125);
DISPLAY 0.489362 (-900 5125);
PAINT SKYBLUE (-900 5125);
FORCEPROP 1 LAST TOLERANCE 10%
J 0
(-900 5075);
DISPLAY 0.489362 (-900 5075);
PAINT SKYBLUE (-900 5075);
FORCEPROP 1 LAST MATERIAL X7R
J 0
(-900 5025);
DISPLAY 0.489362 (-900 5025);
PAINT SKYBLUE (-900 5025);
FORCEPROP 1 LAST VALUE 0.1UF
J 0
(-900 5175);
DISPLAY 0.489362 (-900 5175);
PAINT SKYBLUE (-900 5175);
FORCEPROP 1 LAST PACK_TYPE 0402
J 0
(-900 4925);
DISPLAY 0.489362 (-900 4925);
PAINT SKYBLUE (-900 4925);
FORCEPROP 1 LAST PATH I114
J 0
(-900 5275);
DISPLAY 0.978723 (-900 5275);
PAINT WHITE (-900 5275);
DISPLAY INVISIBLE (-900 5275);
FORCEPROP 1 LAST PART_NUMBER CH4104K1B00
J 0
(-900 4975);
DISPLAY 0.489362 (-900 4975);
PAINT SKYBLUE (-900 4975);
DISPLAY INVISIBLE (-900 4975);
FORCEPROP 2 LAST CDS_LIB pure_quanta
J 0
(-950 5125);
DISPLAY INVISIBLE (-950 5125);
FORCEADD ISL99390FRZTR5935..1
(-6950 1450);
FORCEPROP 1 LAST LOCATION PU6512
J 0
(-7250 2325);
DISPLAY 0.723404 (-7250 2325);
PAINT GREEN (-7250 2325);
FORCEPROP 2 LAST SEC 1
J 0
(-7250 2550);
DISPLAY 0.680851 (-7250 2550);
PAINT MONO (-7250 2550);
DISPLAY INVISIBLE (-7250 2550);
FORCEPROP 2 LASTPIN (-6550 1000) $PN 2
J 0
(-6540 1010);
DISPLAY 0.680851 (-6540 1010);
PAINT MONO (-6540 1010);
FORCEPROP 2 LASTPIN (-6550 1800) $PN 33
J 0
(-6540 1810);
DISPLAY 0.680851 (-6540 1810);
PAINT MONO (-6540 1810);
FORCEPROP 2 LASTPIN (-7400 1200) $PN 31
J 2
(-7410 1210);
DISPLAY 0.680851 (-7410 1210);
PAINT MONO (-7410 1210);
FORCEPROP 2 LASTPIN (-7400 1600) $PN 35
J 2
(-7410 1610);
DISPLAY 0.680851 (-7410 1610);
PAINT MONO (-7410 1610);
FORCEPROP 2 LASTPIN (-6550 1150) $PN 6
J 0
(-6540 1160);
DISPLAY 0.680851 (-6540 1160);
PAINT MONO (-6540 1160);
FORCEPROP 2 LASTPIN (-6550 1100) $PN 41
J 0
(-6540 1110);
DISPLAY 0.680851 (-6540 1110);
PAINT MONO (-6540 1110);
FORCEPROP 2 LASTPIN (-7400 1450) $PN 38
J 2
(-7410 1460);
DISPLAY 0.680851 (-7410 1460);
PAINT MONO (-7410 1460);
FORCEPROP 2 LASTPIN (-7400 1150) $PN 37
J 2
(-7410 1160);
DISPLAY 0.680851 (-7410 1160);
PAINT MONO (-7410 1160);
FORCEPROP 2 LASTPIN (-6550 950) $PN 5
J 0
(-6540 960);
DISPLAY 0.680851 (-6540 960);
PAINT MONO (-6540 960);
FORCEPROP 2 LASTPIN (-6550 900) $PN 7_9-20_24
J 0
(-6540 910);
DISPLAY 0.680851 (-6540 910);
PAINT MONO (-6540 910);
FORCEPROP 2 LASTPIN (-6550 850) $PN 40
J 0
(-6540 860);
DISPLAY 0.680851 (-6540 860);
PAINT MONO (-6540 860);
FORCEPROP 2 LASTPIN (-6550 1550) $PN 32
J 0
(-6540 1560);
DISPLAY 0.680851 (-6540 1560);
PAINT MONO (-6540 1560);
FORCEPROP 2 LASTPIN (-7400 2100) $PN 4
J 2
(-7410 2110);
DISPLAY 0.680851 (-7410 2110);
PAINT MONO (-7410 2110);
FORCEPROP 2 LASTPIN (-7400 850) $PN 34
J 2
(-7410 860);
DISPLAY 0.680851 (-7410 860);
PAINT MONO (-7410 860);
FORCEPROP 2 LASTPIN (-7400 1350) $PN 39
J 2
(-7410 1360);
DISPLAY 0.680851 (-7410 1360);
PAINT MONO (-7410 1360);
FORCEPROP 2 LASTPIN (-6550 1450) $PN 10_19
J 0
(-6540 1460);
DISPLAY 0.680851 (-6540 1460);
PAINT MONO (-6540 1460);
FORCEPROP 2 LASTPIN (-7400 950) $PN 36
J 2
(-7410 960);
DISPLAY 0.680851 (-7410 960);
PAINT MONO (-7410 960);
FORCEPROP 2 LASTPIN (-7400 1800) $PN 3
J 2
(-7410 1810);
DISPLAY 0.680851 (-7410 1810);
PAINT MONO (-7410 1810);
FORCEPROP 2 LASTPIN (-6550 2100) $PN 25_29
J 0
(-6540 2110);
DISPLAY 0.680851 (-6540 2110);
PAINT MONO (-6540 2110);
FORCEPROP 2 LASTPIN (-6550 2050) $PN 30
J 0
(-6540 2060);
DISPLAY 0.680851 (-6540 2060);
PAINT MONO (-6540 2060);
FORCEPROP 2 LASTPIN (-6550 1200) $PN 1
J 0
(-6540 1210);
DISPLAY 0.680851 (-6540 1210);
PAINT MONO (-6540 1210);
FORCEPROP 2 LAST VALUE ISL99390FRZ-TR5935
J 0
(-7250 2425);
DISPLAY 0.617021 (-7250 2425);
FORCEPROP 1 LAST MATERIAL IC
J 0
(-7250 2175);
DISPLAY 0.723404 (-7250 2175);
PAINT GREEN (-7250 2175);
FORCEPROP 2 LAST PART_TYPE SMLF
J 0
(-7250 2500);
DISPLAY 0.680851 (-7250 2500);
FORCEPROP 1 LAST PATH I12
J 0
(-6950 1450);
DISPLAY 0.723404 (-6950 1450);
PAINT GREEN (-6950 1450);
DISPLAY INVISIBLE (-6950 1450);
FORCEPROP 1 LAST PART_NUMBER AL099390004
J 0
(-7250 2250);
DISPLAY 0.723404 (-7250 2250);
PAINT GREEN (-7250 2250);
DISPLAY INVISIBLE (-7250 2250);
FORCEPROP 2 LAST SEC_TYPE 
J 0
(-7250 2550);
DISPLAY 0.680851 (-7250 2550);
DISPLAY INVISIBLE (-7250 2550);
FORCEPROP 2 LAST CDS_LIB pure_quanta
J 0
(-6950 1450);
DISPLAY INVISIBLE (-6950 1450);
FORCEPROP 1 LAST CDS_LMAN_SYM_OUTLINE -300,700,250,-650
J 0
(-6950 1450);
DISPLAY 0.468085 (-6950 1450);
PAINT GREEN (-6950 1450);
DISPLAY INVISIBLE (-6950 1450);
FORCEPROP 1 LAST NEEDS_NO_SIZE TRUE
J 0
(-6950 1450);
DISPLAY 0.723404 (-6950 1450);
PAINT GREEN (-6950 1450);
DISPLAY INVISIBLE (-6950 1450);
FORCEPROP 2 LAST BOM_COST VR_DIMM 
J 0
(-7225 2475);
DISPLAY 0.680851 (-7225 2475);
DISPLAY INVISIBLE (-7225 2475);
FORCEADD UNIVERSAL_GND..1
(-8050 2150);
FORCEPROP 3 LASTPIN (-8050 2200) SIG_NAME GND\g
J 0
(-8040 2210);
DISPLAY 0.659574 (-8040 2210);
PAINT MONO (-8040 2210);
DISPLAY INVISIBLE (-8040 2210);
FORCEPROP 1 LAST PATH I13
J 0
(-7975 2150);
DISPLAY 0.872340 (-7975 2150);
PAINT AQUA (-7975 2150);
DISPLAY INVISIBLE (-7975 2150);
FORCEPROP 1 LAST HDL_POWER GND
J 1
(-8025 2075);
DISPLAY 0.872340 (-8025 2075);
PAINT GREEN (-8025 2075);
DISPLAY INVISIBLE (-8025 2075);
FORCEPROP 2 LAST CDS_LIB pure_quanta_power
J 0
(-8050 2150);
DISPLAY INVISIBLE (-8050 2150);
FORCEADD Q_CAP..1
(-8050 2400);
FORCEPROP 1 LAST LOCATION PC6644_09P1_2
J 0
(-8000 2500);
DISPLAY 0.978723 (-8000 2500);
FORCEPROP 0 LAST $SEC 1
J 0
(-8000 2550);
DISPLAY 0.680851 (-8000 2550);
PAINT MONO (-8000 2550);
DISPLAY INVISIBLE (-8000 2550);
FORCEPROP 0 LAST CDS_SEC 1
J 0
(-8000 2550);
DISPLAY 0.680851 (-8000 2550);
DISPLAY INVISIBLE (-8000 2550);
FORCEPROP 1 LASTPIN (-8050 2500) $PN 1
J 0
(-8040 2480);
DISPLAY 0.787234 (-8040 2480);
PAINT MONO (-8040 2480);
FORCEPROP 1 LASTPIN (-8050 2300) $PN 2
J 0
(-8040 2280);
DISPLAY 0.787234 (-8040 2280);
PAINT MONO (-8040 2280);
FORCEPROP 1 LAST TOLERANCE 10%
J 0
(-8000 2350);
DISPLAY 0.617021 (-8000 2350);
FORCEPROP 1 LAST VOLTAGE 10V
J 0
(-8000 2400);
DISPLAY 0.617021 (-8000 2400);
FORCEPROP 1 LAST PACK_TYPE C0402
J 0
(-8000 2200);
DISPLAY 0.617021 (-8000 2200);
FORCEPROP 1 LAST VALUE 2.2UF
J 0
(-8000 2450);
DISPLAY 0.617021 (-8000 2450);
FORCEPROP 1 LAST MATERIAL X6S
J 0
(-8000 2300);
DISPLAY 0.617021 (-8000 2300);
FORCEPROP 1 LAST PATH I14
J 0
(-8000 2550);
DISPLAY 0.978723 (-8000 2550);
PAINT WHITE (-8000 2550);
DISPLAY INVISIBLE (-8000 2550);
FORCEPROP 1 LAST PART_NUMBER CH5222KEB01
J 0
(-8000 2250);
DISPLAY 0.617021 (-8000 2250);
DISPLAY INVISIBLE (-8000 2250);
FORCEPROP 2 LAST CDS_LIB pure_quanta
J 0
(-8050 2400);
DISPLAY INVISIBLE (-8050 2400);
FORCEPROP 2 LAST BOM_COST VR_DIMM 
J 0
(-8000 2550);
DISPLAY 0.680851 (-8000 2550);
DISPLAY INVISIBLE (-8000 2550);
FORCEADD UNIVERSAL_GND..1
(-6375 650);
FORCEPROP 3 LASTPIN (-6375 700) SIG_NAME GND\g
J 0
(-6365 710);
DISPLAY 0.659574 (-6365 710);
PAINT MONO (-6365 710);
DISPLAY INVISIBLE (-6365 710);
FORCEPROP 1 LAST PATH I15
J 0
(-6300 650);
DISPLAY 0.872340 (-6300 650);
PAINT AQUA (-6300 650);
DISPLAY INVISIBLE (-6300 650);
FORCEPROP 1 LAST HDL_POWER GND
J 1
(-6350 575);
DISPLAY 0.872340 (-6350 575);
PAINT GREEN (-6350 575);
DISPLAY INVISIBLE (-6350 575);
FORCEPROP 2 LAST CDS_LIB pure_quanta_power
J 0
(-6375 650);
DISPLAY INVISIBLE (-6375 650);
FORCEADD Q_RES..1
(-5025 375);
FORCEPROP 1 LAST LOCATION PR6631
J 0
(-5125 300);
DISPLAY 0.978723 (-5125 300);
FORCEPROP 0 LAST $SEC 1
J 0
(-4875 550);
DISPLAY 0.680851 (-4875 550);
PAINT MONO (-4875 550);
DISPLAY INVISIBLE (-4875 550);
FORCEPROP 0 LAST CDS_SEC 1
J 0
(-4875 550);
DISPLAY 0.680851 (-4875 550);
DISPLAY INVISIBLE (-4875 550);
FORCEPROP 1 LASTPIN (-5125 375) $PN 1
J 0
(-5113 387);
DISPLAY 0.787234 (-5113 387);
PAINT MONO (-5113 387);
FORCEPROP 1 LASTPIN (-4925 375) $PN 2
J 0
(-4963 387);
DISPLAY 0.787234 (-4963 387);
PAINT MONO (-4963 387);
FORCEPROP 1 LAST PACK_TYPE 0402LF
J 0
(-4875 500);
DISPLAY 0.617021 (-4875 500);
FORCEPROP 1 LAST WATTAGE 1/16W
J 2
(-4925 500);
DISPLAY 0.617021 (-4925 500);
FORCEPROP 1 LAST TOLERANCE 5%
J 0
(-4800 375);
DISPLAY 0.617021 (-4800 375);
FORCEPROP 1 LAST MATERIAL CHIP
J 0
(-5225 500);
DISPLAY 0.617021 (-5225 500);
FORCEPROP 1 LAST VALUE 0
J 2
(-4850 375);
DISPLAY 0.617021 (-4850 375);
FORCEPROP 1 LAST PATH I16
J 0
(-5075 525);
DISPLAY 0.978723 (-5075 525);
PAINT WHITE (-5075 525);
DISPLAY INVISIBLE (-5075 525);
FORCEPROP 1 LAST PART_NUMBER CS00002JB13
J 0
(-5225 450);
DISPLAY 0.617021 (-5225 450);
DISPLAY INVISIBLE (-5225 450);
FORCEPROP 2 LAST BOM_COST VR_DIMM 
J 0
(-5075 350);
DISPLAY 0.680851 (-5075 350);
DISPLAY INVISIBLE (-5075 350);
FORCEPROP 2 LAST CDS_LIB pure_quanta
J 0
(-5025 375);
DISPLAY INVISIBLE (-5025 375);
FORCEADD UNIVERSAL_GND..1
(-5850 1975);
FORCEPROP 3 LASTPIN (-5850 2025) SIG_NAME GND\g
J 0
(-5840 2035);
DISPLAY 0.659574 (-5840 2035);
PAINT MONO (-5840 2035);
DISPLAY INVISIBLE (-5840 2035);
FORCEPROP 1 LAST PATH I17
J 0
(-5775 1975);
DISPLAY 0.872340 (-5775 1975);
PAINT AQUA (-5775 1975);
DISPLAY INVISIBLE (-5775 1975);
FORCEPROP 1 LAST HDL_POWER GND
J 1
(-5825 1900);
DISPLAY 0.872340 (-5825 1900);
PAINT GREEN (-5825 1900);
DISPLAY INVISIBLE (-5825 1900);
FORCEPROP 2 LAST CDS_LIB pure_quanta_power
J 0
(-5850 1975);
DISPLAY INVISIBLE (-5850 1975);
FORCEADD Q_CAP..1
(-5850 2250);
FORCEPROP 1 LAST LOCATION PC6634_2
J 0
(-5800 2350);
DISPLAY 0.978723 (-5800 2350);
FORCEPROP 0 LAST $SEC 1
J 0
(-5800 2400);
DISPLAY 0.680851 (-5800 2400);
PAINT MONO (-5800 2400);
DISPLAY INVISIBLE (-5800 2400);
FORCEPROP 0 LAST CDS_SEC 1
J 0
(-5800 2400);
DISPLAY 0.680851 (-5800 2400);
DISPLAY INVISIBLE (-5800 2400);
FORCEPROP 1 LASTPIN (-5850 2350) $PN 1
J 0
(-5840 2330);
DISPLAY 0.787234 (-5840 2330);
PAINT MONO (-5840 2330);
FORCEPROP 1 LASTPIN (-5850 2150) $PN 2
J 0
(-5840 2130);
DISPLAY 0.787234 (-5840 2130);
PAINT MONO (-5840 2130);
FORCEPROP 1 LAST PACK_TYPE 0402
J 0
(-5800 2050);
DISPLAY 0.617021 (-5800 2050);
FORCEPROP 1 LAST MATERIAL X7R
J 0
(-5800 2150);
DISPLAY 0.617021 (-5800 2150);
FORCEPROP 1 LAST VALUE 3300PF
J 0
(-5800 2300);
DISPLAY 0.617021 (-5800 2300);
FORCEPROP 1 LAST TOLERANCE 10%
J 0
(-5800 2200);
DISPLAY 0.617021 (-5800 2200);
FORCEPROP 1 LAST VOLTAGE 50V
J 0
(-5800 2250);
DISPLAY 0.617021 (-5800 2250);
FORCEPROP 1 LAST PATH I18
J 0
(-5800 2400);
DISPLAY 0.978723 (-5800 2400);
PAINT WHITE (-5800 2400);
DISPLAY INVISIBLE (-5800 2400);
FORCEPROP 1 LAST PART_NUMBER TMP_QCH2336K1B12
J 0
(-5800 2100);
DISPLAY 0.617021 (-5800 2100);
DISPLAY INVISIBLE (-5800 2100);
FORCEPROP 2 LAST CDS_LIB pure_quanta
J 0
(-5850 2250);
DISPLAY INVISIBLE (-5850 2250);
FORCEPROP 2 LAST BOM_COST VR_DIMM 
J 0
(-5800 2400);
DISPLAY 0.680851 (-5800 2400);
DISPLAY INVISIBLE (-5800 2400);
FORCEADD Q_RES..1
(-5350 1800);
FORCEPROP 1 LAST LOCATION PR6629
J 0
(-5575 1800);
DISPLAY 0.638298 (-5575 1800);
FORCEPROP 0 LAST $SEC 1
J 0
(-5225 1950);
DISPLAY 0.680851 (-5225 1950);
PAINT MONO (-5225 1950);
DISPLAY INVISIBLE (-5225 1950);
FORCEPROP 0 LAST CDS_SEC 1
J 0
(-5225 1950);
DISPLAY 0.680851 (-5225 1950);
DISPLAY INVISIBLE (-5225 1950);
FORCEPROP 1 LASTPIN (-5450 1800) $PN 1
J 0
(-5438 1812);
DISPLAY 0.787234 (-5438 1812);
PAINT MONO (-5438 1812);
FORCEPROP 1 LASTPIN (-5250 1800) $PN 2
J 0
(-5288 1812);
DISPLAY 0.787234 (-5288 1812);
PAINT MONO (-5288 1812);
FORCEPROP 1 LAST VALUE 5.6
J 2
(-5175 1800);
DISPLAY 0.510638 (-5175 1800);
FORCEPROP 1 LAST MATERIAL CHIP
J 0
(-5500 1925);
DISPLAY 0.510638 (-5500 1925);
FORCEPROP 1 LAST PACK_TYPE 0402LF
J 0
(-5225 1925);
DISPLAY 0.510638 (-5225 1925);
FORCEPROP 1 LAST TOLERANCE 1%
J 0
(-5150 1800);
DISPLAY 0.510638 (-5150 1800);
FORCEPROP 1 LAST WATTAGE 1/16W
J 2
(-5250 1925);
DISPLAY 0.510638 (-5250 1925);
FORCEPROP 1 LAST PATH I19
J 0
(-5400 1950);
DISPLAY 0.978723 (-5400 1950);
PAINT WHITE (-5400 1950);
DISPLAY INVISIBLE (-5400 1950);
FORCEPROP 1 LAST PART_NUMBER CS-5602FB01
J 0
(-5500 1875);
DISPLAY 0.510638 (-5500 1875);
DISPLAY INVISIBLE (-5500 1875);
FORCEPROP 2 LAST CDS_LIB pure_quanta
J 0
(-5350 1800);
DISPLAY INVISIBLE (-5350 1800);
FORCEADD Q_CAP..1
(-9500 1025);
FORCEPROP 1 LAST LOCATION PC6646
J 0
(-9450 1125);
DISPLAY 0.978723 (-9450 1125);
FORCEPROP 0 LAST $SEC 1
J 0
(-9450 1175);
DISPLAY 0.680851 (-9450 1175);
PAINT MONO (-9450 1175);
DISPLAY INVISIBLE (-9450 1175);
FORCEPROP 0 LAST CDS_SEC 1
J 0
(-9450 1175);
DISPLAY 0.680851 (-9450 1175);
DISPLAY INVISIBLE (-9450 1175);
FORCEPROP 1 LASTPIN (-9500 1125) $PN 1
J 0
(-9490 1105);
DISPLAY 0.787234 (-9490 1105);
PAINT MONO (-9490 1105);
FORCEPROP 1 LASTPIN (-9500 925) $PN 2
J 0
(-9490 905);
DISPLAY 0.787234 (-9490 905);
PAINT MONO (-9490 905);
FORCEPROP 1 LAST PACK_TYPE C0402
J 0
(-9450 825);
DISPLAY 0.617021 (-9450 825);
FORCEPROP 1 LAST VOLTAGE 50V
J 0
(-9450 1025);
DISPLAY 0.617021 (-9450 1025);
FORCEPROP 1 LAST VALUE 100NF
J 0
(-9450 1075);
DISPLAY 0.617021 (-9450 1075);
FORCEPROP 1 LAST TOLERANCE 10%
J 0
(-9450 975);
DISPLAY 0.617021 (-9450 975);
FORCEPROP 1 LAST MATERIAL X7R
J 0
(-9450 925);
DISPLAY 0.617021 (-9450 925);
FORCEPROP 1 LAST PATH I2
J 0
(-9450 1175);
DISPLAY 0.978723 (-9450 1175);
PAINT WHITE (-9450 1175);
DISPLAY INVISIBLE (-9450 1175);
FORCEPROP 1 LAST PART_NUMBER CH4106K1B01
J 0
(-9450 875);
DISPLAY 0.617021 (-9450 875);
DISPLAY INVISIBLE (-9450 875);
FORCEPROP 2 LAST CDS_LIB pure_quanta
J 0
(-9500 1025);
DISPLAY INVISIBLE (-9500 1025);
FORCEPROP 2 LAST BOM_COST VR_CPU
J 0
(-9450 1175);
DISPLAY 0.680851 (-9450 1175);
DISPLAY INVISIBLE (-9450 1175);
FORCEADD UNIVERSAL_GND..1
(-5350 1975);
FORCEPROP 3 LASTPIN (-5350 2025) SIG_NAME GND\g
J 0
(-5340 2035);
DISPLAY 0.659574 (-5340 2035);
PAINT MONO (-5340 2035);
DISPLAY INVISIBLE (-5340 2035);
FORCEPROP 1 LAST PATH I20
J 0
(-5275 1975);
DISPLAY 0.872340 (-5275 1975);
PAINT AQUA (-5275 1975);
DISPLAY INVISIBLE (-5275 1975);
FORCEPROP 1 LAST HDL_POWER GND
J 1
(-5325 1900);
DISPLAY 0.872340 (-5325 1900);
PAINT GREEN (-5325 1900);
DISPLAY INVISIBLE (-5325 1900);
FORCEPROP 2 LAST CDS_LIB pure_quanta_power
J 0
(-5350 1975);
DISPLAY INVISIBLE (-5350 1975);
FORCEADD Q_CAP..1
(-5350 2250);
FORCEPROP 1 LAST LOCATION PC6633_2
J 0
(-5300 2350);
DISPLAY 0.978723 (-5300 2350);
FORCEPROP 0 LAST $SEC 1
J 0
(-5300 2400);
DISPLAY 0.680851 (-5300 2400);
PAINT MONO (-5300 2400);
DISPLAY INVISIBLE (-5300 2400);
FORCEPROP 0 LAST CDS_SEC 1
J 0
(-5300 2400);
DISPLAY 0.680851 (-5300 2400);
DISPLAY INVISIBLE (-5300 2400);
FORCEPROP 1 LASTPIN (-5350 2350) $PN 1
J 0
(-5340 2330);
DISPLAY 0.787234 (-5340 2330);
PAINT MONO (-5340 2330);
FORCEPROP 1 LASTPIN (-5350 2150) $PN 2
J 0
(-5340 2130);
DISPLAY 0.787234 (-5340 2130);
PAINT MONO (-5340 2130);
FORCEPROP 1 LAST VALUE 1UF
J 0
(-5300 2300);
DISPLAY 0.617021 (-5300 2300);
FORCEPROP 1 LAST MATERIAL X6S
J 0
(-5300 2150);
DISPLAY 0.617021 (-5300 2150);
FORCEPROP 1 LAST PACK_TYPE C0402
J 0
(-5300 2050);
DISPLAY 0.617021 (-5300 2050);
FORCEPROP 1 LAST TOLERANCE 10%
J 0
(-5300 2200);
DISPLAY 0.617021 (-5300 2200);
FORCEPROP 1 LAST VOLTAGE 25V
J 0
(-5300 2250);
DISPLAY 0.617021 (-5300 2250);
FORCEPROP 1 LAST PATH I21
J 0
(-5300 2400);
DISPLAY 0.978723 (-5300 2400);
PAINT WHITE (-5300 2400);
DISPLAY INVISIBLE (-5300 2400);
FORCEPROP 1 LAST PART_NUMBER CH5104KEB02
J 0
(-5300 2100);
DISPLAY 0.617021 (-5300 2100);
DISPLAY INVISIBLE (-5300 2100);
FORCEPROP 2 LAST CDS_LIB pure_quanta
J 0
(-5350 2250);
DISPLAY INVISIBLE (-5350 2250);
FORCEPROP 2 LAST BOM_COST VR_DIMM 
J 0
(-5300 2400);
DISPLAY 0.680851 (-5300 2400);
DISPLAY INVISIBLE (-5300 2400);
FORCEADD Q_INDUCTOR..1
(-4775 1475);
FORCEPROP 1 LAST LOCATION PL6512
J 0
(-5075 1500);
DISPLAY 0.723404 (-5075 1500);
PAINT GREEN (-5075 1500);
FORCEPROP 0 LAST $SEC 1
J 0
(-5075 1550);
DISPLAY 0.680851 (-5075 1550);
PAINT MONO (-5075 1550);
DISPLAY INVISIBLE (-5075 1550);
FORCEPROP 0 LAST CDS_SEC 1
J 0
(-5075 1550);
DISPLAY 0.680851 (-5075 1550);
DISPLAY INVISIBLE (-5075 1550);
FORCEPROP 0 LASTPIN (-4875 1450) $PN 1
J 2
(-4885 1460);
DISPLAY 0.680851 (-4885 1460);
PAINT MONO (-4885 1460);
FORCEPROP 0 LASTPIN (-4675 1450) $PN 2
J 0
(-4665 1460);
DISPLAY 0.680851 (-4665 1460);
PAINT MONO (-4665 1460);
FORCEPROP 2 LAST VALUE 120NH/69A
J 0
(-4600 1475);
DISPLAY 0.617021 (-4600 1475);
FORCEPROP 2 LAST PACK_TYPE SMLF
J 0
(-4450 1400);
DISPLAY 0.617021 (-4450 1400);
FORCEPROP 1 LAST MATERIAL IND
J 0
(-5075 1450);
DISPLAY 0.723404 (-5075 1450);
PAINT GREEN (-5075 1450);
FORCEPROP 1 LAST PATH I22
J 0
(-4700 1530);
DISPLAY 0.723404 (-4700 1530);
PAINT GREEN (-4700 1530);
DISPLAY INVISIBLE (-4700 1530);
FORCEPROP 1 LAST PART_NUMBER CV+12^0EZ03
J 0
(-5075 1400);
DISPLAY 0.723404 (-5075 1400);
PAINT GREEN (-5075 1400);
DISPLAY INVISIBLE (-5075 1400);
FORCEPROP 2 LAST CDS_LIB pure_quanta
J 0
(-4775 1475);
DISPLAY INVISIBLE (-4775 1475);
FORCEPROP 1 LAST NEEDS_NO_SIZE TRUE
J 0
(-4775 1475);
DISPLAY 0.468085 (-4775 1475);
PAINT GREEN (-4775 1475);
DISPLAY INVISIBLE (-4775 1475);
FORCEPROP 2 LAST BOM_COST VR_DIMM 
J 0
(-4600 1525);
DISPLAY 0.680851 (-4600 1525);
DISPLAY INVISIBLE (-4600 1525);
FORCEADD Q_CAP..1
(-4000 1300);
FORCEPROP 1 LAST LOCATION PC6807
J 0
(-3950 1400);
DISPLAY 0.978723 (-3950 1400);
FORCEPROP 0 LAST $SEC 1
J 0
(-3950 1450);
DISPLAY 0.680851 (-3950 1450);
PAINT MONO (-3950 1450);
DISPLAY INVISIBLE (-3950 1450);
FORCEPROP 0 LAST CDS_SEC 1
J 0
(-3950 1450);
DISPLAY 0.680851 (-3950 1450);
DISPLAY INVISIBLE (-3950 1450);
FORCEPROP 1 LASTPIN (-4000 1400) $PN 1
J 0
(-3990 1380);
DISPLAY 0.787234 (-3990 1380);
PAINT MONO (-3990 1380);
FORCEPROP 1 LASTPIN (-4000 1200) $PN 2
J 0
(-3990 1180);
DISPLAY 0.787234 (-3990 1180);
PAINT MONO (-3990 1180);
FORCEPROP 1 LAST TOLERANCE 10%
J 0
(-3950 1250);
DISPLAY 0.489362 (-3950 1250);
FORCEPROP 1 LAST MATERIAL X7R
J 0
(-3950 1200);
DISPLAY 0.489362 (-3950 1200);
FORCEPROP 1 LAST PACK_TYPE C0402
J 0
(-3950 1100);
DISPLAY 0.489362 (-3950 1100);
FORCEPROP 1 LAST VOLTAGE 50V
J 0
(-3950 1300);
DISPLAY 0.489362 (-3950 1300);
FORCEPROP 1 LAST VALUE 100NF
J 0
(-3950 1350);
DISPLAY 0.489362 (-3950 1350);
FORCEPROP 1 LAST PATH I23
J 0
(-3950 1450);
DISPLAY 0.978723 (-3950 1450);
PAINT WHITE (-3950 1450);
DISPLAY INVISIBLE (-3950 1450);
FORCEPROP 1 LAST PART_NUMBER CH4106K1B01
J 0
(-3950 1150);
DISPLAY 0.489362 (-3950 1150);
DISPLAY INVISIBLE (-3950 1150);
FORCEPROP 2 LAST BOM_COST VR_DIMM 
J 0
(-3950 1450);
DISPLAY 0.680851 (-3950 1450);
DISPLAY INVISIBLE (-3950 1450);
FORCEPROP 2 LAST CDS_LIB pure_quanta
J 0
(-4000 1300);
DISPLAY INVISIBLE (-4000 1300);
FORCEADD UNIVERSAL_GND..1
(-4850 1975);
FORCEPROP 3 LASTPIN (-4850 2025) SIG_NAME GND\g
J 0
(-4840 2035);
DISPLAY 0.659574 (-4840 2035);
PAINT MONO (-4840 2035);
DISPLAY INVISIBLE (-4840 2035);
FORCEPROP 1 LAST PATH I24
J 0
(-4775 1975);
DISPLAY 0.872340 (-4775 1975);
PAINT AQUA (-4775 1975);
DISPLAY INVISIBLE (-4775 1975);
FORCEPROP 1 LAST HDL_POWER GND
J 1
(-4825 1900);
DISPLAY 0.872340 (-4825 1900);
PAINT GREEN (-4825 1900);
DISPLAY INVISIBLE (-4825 1900);
FORCEPROP 2 LAST CDS_LIB pure_quanta_power
J 0
(-4850 1975);
DISPLAY INVISIBLE (-4850 1975);
FORCEADD Q_CAP..1
(-4850 2250);
FORCEPROP 1 LAST LOCATION PC6635_2
J 0
(-4800 2350);
DISPLAY 0.978723 (-4800 2350);
FORCEPROP 0 LAST $SEC 1
J 0
(-4800 2400);
DISPLAY 0.680851 (-4800 2400);
PAINT MONO (-4800 2400);
DISPLAY INVISIBLE (-4800 2400);
FORCEPROP 0 LAST CDS_SEC 1
J 0
(-4800 2400);
DISPLAY 0.680851 (-4800 2400);
DISPLAY INVISIBLE (-4800 2400);
FORCEPROP 1 LASTPIN (-4850 2350) $PN 1
J 0
(-4840 2330);
DISPLAY 0.787234 (-4840 2330);
PAINT MONO (-4840 2330);
FORCEPROP 1 LASTPIN (-4850 2150) $PN 2
J 0
(-4840 2130);
DISPLAY 0.787234 (-4840 2130);
PAINT MONO (-4840 2130);
FORCEPROP 1 LAST PACK_TYPE C0805
J 0
(-4800 2050);
DISPLAY 0.638298 (-4800 2050);
FORCEPROP 1 LAST MATERIAL X6S
J 0
(-4800 2150);
DISPLAY 0.638298 (-4800 2150);
FORCEPROP 1 LAST TOLERANCE 20%
J 0
(-4800 2200);
DISPLAY 0.638298 (-4800 2200);
FORCEPROP 1 LAST VALUE 22UF
J 0
(-4800 2300);
DISPLAY 0.638298 (-4800 2300);
FORCEPROP 1 LAST VOLTAGE 16V
J 0
(-4800 2250);
DISPLAY 0.638298 (-4800 2250);
FORCEPROP 1 LAST PATH I25
J 0
(-4800 2400);
DISPLAY 0.978723 (-4800 2400);
PAINT WHITE (-4800 2400);
DISPLAY INVISIBLE (-4800 2400);
FORCEPROP 1 LAST PART_NUMBER CH6223MEA01
J 0
(-4800 2100);
DISPLAY 0.638298 (-4800 2100);
DISPLAY INVISIBLE (-4800 2100);
FORCEPROP 2 LAST CDS_LIB pure_quanta
J 0
(-4850 2250);
DISPLAY INVISIBLE (-4850 2250);
FORCEPROP 0 LAST REUSE_ID 41
J 0
(-4800 2450);
DISPLAY 0.680851 (-4800 2450);
DISPLAY INVISIBLE (-4800 2450);
FORCEPROP 2 LAST BOM_COST VR_DIMM 
J 0
(-4800 2400);
DISPLAY 0.680851 (-4800 2400);
DISPLAY INVISIBLE (-4800 2400);
FORCEADD Q_CAP..2
(-3975 1800);
FORCEPROP 1 LAST LOCATION PC6640
J 1
(-3975 1900);
DISPLAY 0.978723 (-3975 1900);
FORCEPROP 0 LAST $SEC 1
J 0
(-3975 1950);
DISPLAY 0.680851 (-3975 1950);
PAINT MONO (-3975 1950);
DISPLAY INVISIBLE (-3975 1950);
FORCEPROP 0 LAST CDS_SEC 1
J 0
(-3975 1950);
DISPLAY 0.680851 (-3975 1950);
DISPLAY INVISIBLE (-3975 1950);
FORCEPROP 1 LASTPIN (-4075 1800) $PN 1
J 0
(-4085 1815);
DISPLAY 0.787234 (-4085 1815);
PAINT MONO (-4085 1815);
FORCEPROP 1 LASTPIN (-3875 1800) $PN 2
J 0
(-3890 1815);
DISPLAY 0.787234 (-3890 1815);
PAINT MONO (-3890 1815);
FORCEPROP 1 LAST MATERIAL X7R
J 0
(-3975 1650);
DISPLAY 0.617021 (-3975 1650);
FORCEPROP 1 LAST TOLERANCE 10%
J 2
(-3975 1650);
DISPLAY 0.617021 (-3975 1650);
FORCEPROP 1 LAST VOLTAGE 50V
J 0
(-3975 1700);
DISPLAY 0.617021 (-3975 1700);
FORCEPROP 1 LAST VALUE 100NF
J 2
(-3975 1700);
DISPLAY 0.617021 (-3975 1700);
FORCEPROP 1 LAST PACK_TYPE C0402
J 1
(-3975 1600);
DISPLAY 0.617021 (-3975 1600);
FORCEPROP 1 LAST PATH I26
J 0
(-3975 2000);
DISPLAY 0.978723 (-3975 2000);
PAINT WHITE (-3975 2000);
DISPLAY INVISIBLE (-3975 2000);
FORCEPROP 1 LAST PART_NUMBER CH4106K1B01
J 1
(-3975 1850);
DISPLAY 0.617021 (-3975 1850);
DISPLAY INVISIBLE (-3975 1850);
FORCEPROP 2 LAST CDS_LIB pure_quanta
J 0
(-3975 1800);
DISPLAY INVISIBLE (-3975 1800);
FORCEPROP 2 LAST BOM_COST VR_DIMM 
J 0
(-3975 1950);
DISPLAY 0.680851 (-3975 1950);
DISPLAY INVISIBLE (-3975 1950);
FORCEPROP 0 LAST REUSE_ID 55
J 0
(-4000 1900);
DISPLAY 0.680851 (-4000 1900);
DISPLAY INVISIBLE (-4000 1900);
FORCEADD UNIVERSAL_GND..1
(-4350 1975);
FORCEPROP 3 LASTPIN (-4350 2025) SIG_NAME GND\g
J 0
(-4340 2035);
DISPLAY 0.659574 (-4340 2035);
PAINT MONO (-4340 2035);
DISPLAY INVISIBLE (-4340 2035);
FORCEPROP 1 LAST PATH I27
J 0
(-4275 1975);
DISPLAY 0.872340 (-4275 1975);
PAINT AQUA (-4275 1975);
DISPLAY INVISIBLE (-4275 1975);
FORCEPROP 1 LAST HDL_POWER GND
J 1
(-4325 1900);
DISPLAY 0.872340 (-4325 1900);
PAINT GREEN (-4325 1900);
DISPLAY INVISIBLE (-4325 1900);
FORCEPROP 2 LAST CDS_LIB pure_quanta_power
J 0
(-4350 1975);
DISPLAY INVISIBLE (-4350 1975);
FORCEADD Q_CAP..1
(-4350 2250);
FORCEPROP 1 LAST LOCATION PC6636_2
J 0
(-4300 2350);
DISPLAY 0.978723 (-4300 2350);
FORCEPROP 0 LAST $SEC 1
J 0
(-4300 2400);
DISPLAY 0.680851 (-4300 2400);
PAINT MONO (-4300 2400);
DISPLAY INVISIBLE (-4300 2400);
FORCEPROP 0 LAST CDS_SEC 1
J 0
(-4300 2400);
DISPLAY 0.680851 (-4300 2400);
DISPLAY INVISIBLE (-4300 2400);
FORCEPROP 1 LASTPIN (-4350 2350) $PN 1
J 0
(-4340 2330);
DISPLAY 0.787234 (-4340 2330);
PAINT MONO (-4340 2330);
FORCEPROP 1 LASTPIN (-4350 2150) $PN 2
J 0
(-4340 2130);
DISPLAY 0.787234 (-4340 2130);
PAINT MONO (-4340 2130);
FORCEPROP 1 LAST PACK_TYPE C0805
J 0
(-4300 2050);
DISPLAY 0.638298 (-4300 2050);
FORCEPROP 1 LAST TOLERANCE 20%
J 0
(-4300 2200);
DISPLAY 0.638298 (-4300 2200);
FORCEPROP 1 LAST MATERIAL X6S
J 0
(-4300 2150);
DISPLAY 0.638298 (-4300 2150);
FORCEPROP 1 LAST VALUE 22UF
J 0
(-4300 2300);
DISPLAY 0.638298 (-4300 2300);
FORCEPROP 1 LAST VOLTAGE 16V
J 0
(-4300 2250);
DISPLAY 0.638298 (-4300 2250);
FORCEPROP 1 LAST PATH I28
J 0
(-4300 2400);
DISPLAY 0.978723 (-4300 2400);
PAINT WHITE (-4300 2400);
DISPLAY INVISIBLE (-4300 2400);
FORCEPROP 1 LAST PART_NUMBER CH6223MEA01
J 0
(-4300 2100);
DISPLAY 0.638298 (-4300 2100);
DISPLAY INVISIBLE (-4300 2100);
FORCEPROP 2 LAST CDS_LIB pure_quanta
J 0
(-4350 2250);
DISPLAY INVISIBLE (-4350 2250);
FORCEPROP 0 LAST REUSE_ID 41
J 0
(-4300 2450);
DISPLAY 0.680851 (-4300 2450);
DISPLAY INVISIBLE (-4300 2450);
FORCEPROP 2 LAST BOM_COST VR_DIMM 
J 0
(-4300 2400);
DISPLAY 0.680851 (-4300 2400);
DISPLAY INVISIBLE (-4300 2400);
FORCEADD Q_CAP..1
(-3675 1300);
FORCEPROP 1 LAST LOCATION PC6642_2
J 0
(-3650 1400);
DISPLAY 0.638298 (-3650 1400);
FORCEPROP 0 LAST $SEC 1
J 0
(-3650 1450);
DISPLAY 0.680851 (-3650 1450);
PAINT MONO (-3650 1450);
DISPLAY INVISIBLE (-3650 1450);
FORCEPROP 0 LAST CDS_SEC 1
J 0
(-3650 1450);
DISPLAY 0.680851 (-3650 1450);
DISPLAY INVISIBLE (-3650 1450);
FORCEPROP 1 LASTPIN (-3675 1400) $PN 1
J 0
(-3665 1380);
DISPLAY 0.787234 (-3665 1380);
PAINT MONO (-3665 1380);
FORCEPROP 1 LASTPIN (-3675 1200) $PN 2
J 0
(-3665 1180);
DISPLAY 0.787234 (-3665 1180);
PAINT MONO (-3665 1180);
FORCEPROP 1 LAST PACK_TYPE C0805
J 0
(-3625 1150);
DISPLAY 0.510638 (-3625 1150);
FORCEPROP 1 LAST VOLTAGE 4V
J 0
(-3625 1300);
DISPLAY 0.510638 (-3625 1300);
FORCEPROP 1 LAST VALUE 22UF
J 0
(-3625 1350);
DISPLAY 0.510638 (-3625 1350);
FORCEPROP 1 LAST MATERIAL X6S
J 0
(-3625 1200);
DISPLAY 0.510638 (-3625 1200);
FORCEPROP 1 LAST TOLERANCE 20%
J 0
(-3625 1250);
DISPLAY 0.510638 (-3625 1250);
FORCEPROP 1 LAST PATH I29
J 0
(-3625 1450);
DISPLAY 0.978723 (-3625 1450);
PAINT WHITE (-3625 1450);
DISPLAY INVISIBLE (-3625 1450);
FORCEPROP 1 LAST PART_NUMBER CH622KMEA03
J 0
(-3625 1100);
DISPLAY 0.510638 (-3625 1100);
DISPLAY INVISIBLE (-3625 1100);
FORCEPROP 2 LAST CDS_LIB pure_quanta
J 0
(-3675 1300);
DISPLAY INVISIBLE (-3675 1300);
FORCEADD OFFPAGE..2
R 2
(-9300 1450);
FORCEPROP 2 LAST $XR0 365 
J 0
(-9555 1450);
DISPLAY 0.638298 (-9555 1450);
PAINT MONO (-9555 1450);
FORCEPROP 2 LAST PATH I3
J 0
(-9250 1525);
DISPLAY 0.680851 (-9250 1525);
DISPLAY INVISIBLE (-9250 1525);
FORCEPROP 1 LAST COMMENT_BODY TRUE
J 2
(-9255 1355);
DISPLAY 1.170213 (-9255 1355);
PAINT GREEN (-9255 1355);
DISPLAY INVISIBLE (-9255 1355);
FORCEPROP 1 LAST OFFPAGE TRUE
J 2
(-9625 1325);
DISPLAY 1.170213 (-9625 1325);
PAINT GREEN (-9625 1325);
DISPLAY INVISIBLE (-9625 1325);
FORCEPROP 2 LAST CDS_LIB standard
J 0
(-9300 1450);
DISPLAY INVISIBLE (-9300 1450);
FORCEPROP 2 LAST BOM_COST VR_DIMM 
J 0
(-9581 1500);
DISPLAY 0.680851 (-9581 1500);
DISPLAY INVISIBLE (-9581 1500);
FORCEADD Q_CAP..1
(-3450 1300);
FORCEPROP 1 LAST LOCATION PC6643_2
J 0
(-3425 1400);
DISPLAY 0.638298 (-3425 1400);
FORCEPROP 0 LAST $SEC 1
J 0
(-3425 1450);
DISPLAY 0.680851 (-3425 1450);
PAINT MONO (-3425 1450);
DISPLAY INVISIBLE (-3425 1450);
FORCEPROP 0 LAST CDS_SEC 1
J 0
(-3425 1450);
DISPLAY 0.680851 (-3425 1450);
DISPLAY INVISIBLE (-3425 1450);
FORCEPROP 1 LASTPIN (-3450 1400) $PN 1
J 0
(-3440 1380);
DISPLAY 0.787234 (-3440 1380);
PAINT MONO (-3440 1380);
FORCEPROP 1 LASTPIN (-3450 1200) $PN 2
J 0
(-3440 1180);
DISPLAY 0.787234 (-3440 1180);
PAINT MONO (-3440 1180);
FORCEPROP 1 LAST VOLTAGE 4V
J 0
(-3400 1300);
DISPLAY 0.510638 (-3400 1300);
FORCEPROP 1 LAST MATERIAL X6S
J 0
(-3400 1200);
DISPLAY 0.510638 (-3400 1200);
FORCEPROP 1 LAST PACK_TYPE C0805
J 0
(-3400 1150);
DISPLAY 0.510638 (-3400 1150);
FORCEPROP 1 LAST VALUE 22UF
J 0
(-3400 1350);
DISPLAY 0.510638 (-3400 1350);
FORCEPROP 1 LAST TOLERANCE 20%
J 0
(-3400 1250);
DISPLAY 0.510638 (-3400 1250);
FORCEPROP 1 LAST PATH I30
J 0
(-3400 1450);
DISPLAY 0.978723 (-3400 1450);
PAINT WHITE (-3400 1450);
DISPLAY INVISIBLE (-3400 1450);
FORCEPROP 1 LAST PART_NUMBER CH622KMEA03
J 0
(-3400 1150);
DISPLAY 0.510638 (-3400 1150);
DISPLAY INVISIBLE (-3400 1150);
FORCEPROP 2 LAST CDS_LIB pure_quanta
J 0
(-3450 1300);
DISPLAY INVISIBLE (-3450 1300);
FORCEADD Q_CAPP..1
(-3225 1300);
FORCEPROP 1 LAST LOCATION PC6813
J 0
(-3175 1400);
DISPLAY 0.638298 (-3175 1400);
FORCEPROP 0 LAST $SEC 1
J 0
(-3175 1450);
DISPLAY 0.680851 (-3175 1450);
PAINT MONO (-3175 1450);
DISPLAY INVISIBLE (-3175 1450);
FORCEPROP 0 LAST CDS_SEC 1
J 0
(-3175 1450);
DISPLAY 0.680851 (-3175 1450);
DISPLAY INVISIBLE (-3175 1450);
FORCEPROP 1 LASTPIN (-3225 1400) $PN 1
J 0
(-3215 1385);
DISPLAY 0.787234 (-3215 1385);
PAINT MONO (-3215 1385);
FORCEPROP 1 LASTPIN (-3225 1200) $PN 2
J 0
(-3215 1185);
DISPLAY 0.787234 (-3215 1185);
PAINT MONO (-3215 1185);
FORCEPROP 1 LAST MATERIAL SPCAP
J 0
(-3175 1200);
DISPLAY 0.510638 (-3175 1200);
FORCEPROP 1 LAST VOLTAGE 2.5V
J 0
(-3175 1250);
DISPLAY 0.510638 (-3175 1250);
FORCEPROP 1 LAST PACK_TYPE SMLF
J 0
(-3175 1150);
DISPLAY 0.510638 (-3175 1150);
FORCEPROP 1 LAST TOLERANCE 20%
J 0
(-3175 1300);
DISPLAY 0.510638 (-3175 1300);
FORCEPROP 1 LAST VALUE 470UF
J 0
(-3175 1350);
DISPLAY 0.510638 (-3175 1350);
FORCEPROP 1 LAST PATH I31
J 0
(-3175 1450);
DISPLAY 0.978723 (-3175 1450);
DISPLAY INVISIBLE (-3175 1450);
FORCEPROP 1 LAST PART_NUMBER CH747LM8818
J 0
(-3175 1100);
DISPLAY 0.510638 (-3175 1100);
DISPLAY INVISIBLE (-3175 1100);
FORCEPROP 2 LAST CDS_LIB pure_quanta
J 0
(-3225 1300);
DISPLAY INVISIBLE (-3225 1300);
FORCEADD Q_CAPP..1
(-3000 1300);
FORCEPROP 1 LAST LOCATION PC6814
J 0
(-2950 1400);
DISPLAY 0.638298 (-2950 1400);
FORCEPROP 0 LAST $SEC 1
J 0
(-2950 1450);
DISPLAY 0.680851 (-2950 1450);
PAINT MONO (-2950 1450);
DISPLAY INVISIBLE (-2950 1450);
FORCEPROP 0 LAST CDS_SEC 1
J 0
(-2950 1450);
DISPLAY 0.680851 (-2950 1450);
DISPLAY INVISIBLE (-2950 1450);
FORCEPROP 1 LASTPIN (-3000 1400) $PN 1
J 0
(-2990 1385);
DISPLAY 0.787234 (-2990 1385);
PAINT MONO (-2990 1385);
FORCEPROP 1 LASTPIN (-3000 1200) $PN 2
J 0
(-2990 1185);
DISPLAY 0.787234 (-2990 1185);
PAINT MONO (-2990 1185);
FORCEPROP 1 LAST MATERIAL SPCAP
J 0
(-2950 1200);
DISPLAY 0.510638 (-2950 1200);
FORCEPROP 1 LAST VOLTAGE 2.5V
J 0
(-2950 1250);
DISPLAY 0.510638 (-2950 1250);
FORCEPROP 1 LAST VALUE 470UF
J 0
(-2950 1350);
DISPLAY 0.510638 (-2950 1350);
FORCEPROP 1 LAST PACK_TYPE SMLF
J 0
(-2950 1150);
DISPLAY 0.510638 (-2950 1150);
FORCEPROP 1 LAST TOLERANCE 20%
J 0
(-2950 1300);
DISPLAY 0.510638 (-2950 1300);
FORCEPROP 1 LAST PATH I32
J 0
(-2950 1450);
DISPLAY 0.978723 (-2950 1450);
DISPLAY INVISIBLE (-2950 1450);
FORCEPROP 1 LAST PART_NUMBER CH747LM8818
J 0
(-2950 1100);
DISPLAY 0.510638 (-2950 1100);
DISPLAY INVISIBLE (-2950 1100);
FORCEPROP 2 LAST CDS_LIB pure_quanta
J 0
(-3000 1300);
DISPLAY INVISIBLE (-3000 1300);
FORCEADD UNIVERSAL_GND..1
(-3875 1975);
FORCEPROP 3 LASTPIN (-3875 2025) SIG_NAME GND\g
J 0
(-3865 2035);
DISPLAY 0.659574 (-3865 2035);
PAINT MONO (-3865 2035);
DISPLAY INVISIBLE (-3865 2035);
FORCEPROP 1 LAST PATH I33
J 0
(-3800 1975);
DISPLAY 0.872340 (-3800 1975);
PAINT AQUA (-3800 1975);
DISPLAY INVISIBLE (-3800 1975);
FORCEPROP 1 LAST HDL_POWER GND
J 1
(-3850 1900);
DISPLAY 0.872340 (-3850 1900);
PAINT GREEN (-3850 1900);
DISPLAY INVISIBLE (-3850 1900);
FORCEPROP 2 LAST CDS_LIB pure_quanta_power
J 0
(-3875 1975);
DISPLAY INVISIBLE (-3875 1975);
FORCEADD UNIVERSAL_GND..1
(-3500 1975);
FORCEPROP 3 LASTPIN (-3500 2025) SIG_NAME GND\g
J 0
(-3490 2035);
DISPLAY 0.659574 (-3490 2035);
PAINT MONO (-3490 2035);
DISPLAY INVISIBLE (-3490 2035);
FORCEPROP 1 LAST PATH I34
J 0
(-3425 1975);
DISPLAY 0.872340 (-3425 1975);
PAINT AQUA (-3425 1975);
DISPLAY INVISIBLE (-3425 1975);
FORCEPROP 1 LAST HDL_POWER GND
J 1
(-3475 1900);
DISPLAY 0.872340 (-3475 1900);
PAINT GREEN (-3475 1900);
DISPLAY INVISIBLE (-3475 1900);
FORCEPROP 2 LAST CDS_LIB pure_quanta_power
J 0
(-3500 1975);
DISPLAY INVISIBLE (-3500 1975);
FORCEADD Q_CAP..1
(-3875 2250);
FORCEPROP 1 LAST LOCATION PC6637_2
J 0
(-3825 2350);
DISPLAY 0.978723 (-3825 2350);
FORCEPROP 0 LAST $SEC 1
J 0
(-3825 2400);
DISPLAY 0.680851 (-3825 2400);
PAINT MONO (-3825 2400);
DISPLAY INVISIBLE (-3825 2400);
FORCEPROP 0 LAST CDS_SEC 1
J 0
(-3825 2400);
DISPLAY 0.680851 (-3825 2400);
DISPLAY INVISIBLE (-3825 2400);
FORCEPROP 1 LASTPIN (-3875 2350) $PN 1
J 0
(-3865 2330);
DISPLAY 0.787234 (-3865 2330);
PAINT MONO (-3865 2330);
FORCEPROP 1 LASTPIN (-3875 2150) $PN 2
J 0
(-3865 2130);
DISPLAY 0.787234 (-3865 2130);
PAINT MONO (-3865 2130);
FORCEPROP 1 LAST PACK_TYPE C0805
J 0
(-3825 2050);
DISPLAY 0.638298 (-3825 2050);
FORCEPROP 1 LAST TOLERANCE 20%
J 0
(-3825 2200);
DISPLAY 0.638298 (-3825 2200);
FORCEPROP 1 LAST VALUE 22UF
J 0
(-3825 2300);
DISPLAY 0.638298 (-3825 2300);
FORCEPROP 1 LAST VOLTAGE 16V
J 0
(-3825 2250);
DISPLAY 0.638298 (-3825 2250);
FORCEPROP 1 LAST MATERIAL X6S
J 0
(-3825 2150);
DISPLAY 0.638298 (-3825 2150);
FORCEPROP 1 LAST PATH I35
J 0
(-3825 2400);
DISPLAY 0.978723 (-3825 2400);
PAINT WHITE (-3825 2400);
DISPLAY INVISIBLE (-3825 2400);
FORCEPROP 1 LAST PART_NUMBER CH6223MEA01
J 0
(-3825 2100);
DISPLAY 0.638298 (-3825 2100);
DISPLAY INVISIBLE (-3825 2100);
FORCEPROP 2 LAST CDS_LIB pure_quanta
J 0
(-3875 2250);
DISPLAY INVISIBLE (-3875 2250);
FORCEPROP 2 LAST BOM_COST VR_DIMM 
J 0
(-3825 2400);
DISPLAY 0.680851 (-3825 2400);
DISPLAY INVISIBLE (-3825 2400);
FORCEPROP 0 LAST REUSE_ID 41
J 0
(-3825 2450);
DISPLAY 0.680851 (-3825 2450);
DISPLAY INVISIBLE (-3825 2450);
FORCEADD Q_CAP..1
(-3500 2250);
FORCEPROP 1 LAST LOCATION PC6638_2
J 0
(-3450 2350);
DISPLAY 0.978723 (-3450 2350);
FORCEPROP 0 LAST $SEC 1
J 0
(-3450 2400);
DISPLAY 0.680851 (-3450 2400);
PAINT MONO (-3450 2400);
DISPLAY INVISIBLE (-3450 2400);
FORCEPROP 0 LAST CDS_SEC 1
J 0
(-3450 2400);
DISPLAY 0.680851 (-3450 2400);
DISPLAY INVISIBLE (-3450 2400);
FORCEPROP 1 LASTPIN (-3500 2350) $PN 1
J 0
(-3490 2330);
DISPLAY 0.787234 (-3490 2330);
PAINT MONO (-3490 2330);
FORCEPROP 1 LASTPIN (-3500 2150) $PN 2
J 0
(-3490 2130);
DISPLAY 0.787234 (-3490 2130);
PAINT MONO (-3490 2130);
FORCEPROP 1 LAST TOLERANCE 20%
J 0
(-3450 2200);
DISPLAY 0.638298 (-3450 2200);
FORCEPROP 1 LAST MATERIAL X6S
J 0
(-3450 2150);
DISPLAY 0.638298 (-3450 2150);
FORCEPROP 1 LAST PACK_TYPE C0805
J 0
(-3450 2050);
DISPLAY 0.638298 (-3450 2050);
FORCEPROP 1 LAST VOLTAGE 16V
J 0
(-3450 2250);
DISPLAY 0.638298 (-3450 2250);
FORCEPROP 1 LAST VALUE 22UF
J 0
(-3450 2300);
DISPLAY 0.638298 (-3450 2300);
FORCEPROP 1 LAST PATH I36
J 0
(-3450 2400);
DISPLAY 0.978723 (-3450 2400);
PAINT WHITE (-3450 2400);
DISPLAY INVISIBLE (-3450 2400);
FORCEPROP 1 LAST PART_NUMBER CH6223MEA01
J 0
(-3450 2100);
DISPLAY 0.638298 (-3450 2100);
DISPLAY INVISIBLE (-3450 2100);
FORCEPROP 2 LAST CDS_LIB pure_quanta
J 0
(-3500 2250);
DISPLAY INVISIBLE (-3500 2250);
FORCEPROP 0 LAST REUSE_ID 41
J 0
(-3450 2450);
DISPLAY 0.680851 (-3450 2450);
DISPLAY INVISIBLE (-3450 2450);
FORCEPROP 2 LAST BOM_COST VR_DIMM 
J 0
(-3450 2400);
DISPLAY 0.680851 (-3450 2400);
DISPLAY INVISIBLE (-3450 2400);
FORCEADD UNIVERSAL_GND..1
(-3100 1975);
FORCEPROP 3 LASTPIN (-3100 2025) SIG_NAME GND\g
J 0
(-3090 2035);
DISPLAY 0.659574 (-3090 2035);
PAINT MONO (-3090 2035);
DISPLAY INVISIBLE (-3090 2035);
FORCEPROP 1 LAST PATH I37
J 0
(-3025 1975);
DISPLAY 0.872340 (-3025 1975);
PAINT AQUA (-3025 1975);
DISPLAY INVISIBLE (-3025 1975);
FORCEPROP 1 LAST HDL_POWER GND
J 1
(-3075 1900);
DISPLAY 0.872340 (-3075 1900);
PAINT GREEN (-3075 1900);
DISPLAY INVISIBLE (-3075 1900);
FORCEPROP 2 LAST CDS_LIB pure_quanta_power
J 0
(-3100 1975);
DISPLAY INVISIBLE (-3100 1975);
FORCEADD Q_CAP..1
(-3100 2200);
FORCEPROP 1 LAST LOCATION PC6639
J 0
(-3050 2300);
DISPLAY 0.978723 (-3050 2300);
FORCEPROP 0 LAST $SEC 1
J 0
(-3050 2350);
DISPLAY 0.680851 (-3050 2350);
PAINT MONO (-3050 2350);
DISPLAY INVISIBLE (-3050 2350);
FORCEPROP 0 LAST CDS_SEC 1
J 0
(-3050 2350);
DISPLAY 0.680851 (-3050 2350);
DISPLAY INVISIBLE (-3050 2350);
FORCEPROP 1 LASTPIN (-3100 2300) $PN 1
J 0
(-3090 2280);
DISPLAY 0.787234 (-3090 2280);
PAINT MONO (-3090 2280);
FORCEPROP 1 LASTPIN (-3100 2100) $PN 2
J 0
(-3090 2080);
DISPLAY 0.787234 (-3090 2080);
PAINT MONO (-3090 2080);
FORCEPROP 1 LAST TOLERANCE 20%
J 0
(-3050 2150);
DISPLAY 0.510638 (-3050 2150);
FORCEPROP 1 LAST MATERIAL X6S
J 0
(-3050 2100);
DISPLAY 0.510638 (-3050 2100);
FORCEPROP 1 LAST PACK_TYPE C0805
J 0
(-3050 2000);
DISPLAY 0.510638 (-3050 2000);
FORCEPROP 1 LAST VOLTAGE 16V
J 0
(-3050 2200);
DISPLAY 0.510638 (-3050 2200);
FORCEPROP 1 LAST VALUE 22UF
J 0
(-3050 2250);
DISPLAY 0.510638 (-3050 2250);
FORCEPROP 1 LAST PATH I38
J 0
(-3050 2350);
DISPLAY 0.978723 (-3050 2350);
PAINT WHITE (-3050 2350);
DISPLAY INVISIBLE (-3050 2350);
FORCEPROP 1 LAST PART_NUMBER CH6223MEA01
J 0
(-3050 2050);
DISPLAY 0.510638 (-3050 2050);
DISPLAY INVISIBLE (-3050 2050);
FORCEPROP 2 LAST CDS_LIB pure_quanta
J 0
(-3100 2200);
DISPLAY INVISIBLE (-3100 2200);
FORCEADD Q_CAP..1
(-9625 3925);
FORCEPROP 1 LAST LOCATION PC6611_1
J 0
(-9575 4025);
DISPLAY 0.978723 (-9575 4025);
FORCEPROP 0 LAST $SEC 1
J 0
(-9575 4075);
DISPLAY 0.680851 (-9575 4075);
PAINT MONO (-9575 4075);
DISPLAY INVISIBLE (-9575 4075);
FORCEPROP 0 LAST CDS_SEC 1
J 0
(-9575 4075);
DISPLAY 0.680851 (-9575 4075);
DISPLAY INVISIBLE (-9575 4075);
FORCEPROP 1 LASTPIN (-9625 4025) $PN 1
J 0
(-9615 4005);
DISPLAY 0.787234 (-9615 4005);
PAINT MONO (-9615 4005);
FORCEPROP 1 LASTPIN (-9625 3825) $PN 2
J 0
(-9615 3805);
DISPLAY 0.787234 (-9615 3805);
PAINT MONO (-9615 3805);
FORCEPROP 1 LAST VOLTAGE 50V
J 0
(-9575 3925);
DISPLAY 0.617021 (-9575 3925);
FORCEPROP 1 LAST TOLERANCE 10%
J 0
(-9575 3875);
DISPLAY 0.617021 (-9575 3875);
FORCEPROP 1 LAST VALUE 100NF
J 0
(-9575 3975);
DISPLAY 0.617021 (-9575 3975);
FORCEPROP 1 LAST MATERIAL X7R
J 0
(-9575 3825);
DISPLAY 0.617021 (-9575 3825);
FORCEPROP 1 LAST PACK_TYPE C0402
J 0
(-9575 3725);
DISPLAY 0.617021 (-9575 3725);
FORCEPROP 1 LAST PATH I39
J 0
(-9575 4075);
DISPLAY 0.978723 (-9575 4075);
PAINT WHITE (-9575 4075);
DISPLAY INVISIBLE (-9575 4075);
FORCEPROP 1 LAST PART_NUMBER CH4106K1B01
J 0
(-9575 3775);
DISPLAY 0.617021 (-9575 3775);
DISPLAY INVISIBLE (-9575 3775);
FORCEPROP 2 LAST CDS_LIB pure_quanta
J 0
(-9625 3925);
DISPLAY INVISIBLE (-9625 3925);
FORCEPROP 2 LAST BOM_COST VR_CPU
J 0
(-9575 4075);
DISPLAY 0.680851 (-9575 4075);
DISPLAY INVISIBLE (-9575 4075);
FORCEADD UNIVERSAL_GND..1
(-8700 650);
FORCEPROP 3 LASTPIN (-8700 700) SIG_NAME GND\g
J 0
(-8690 710);
DISPLAY 0.659574 (-8690 710);
PAINT MONO (-8690 710);
DISPLAY INVISIBLE (-8690 710);
FORCEPROP 1 LAST PATH I4
J 0
(-8625 650);
DISPLAY 0.872340 (-8625 650);
PAINT AQUA (-8625 650);
DISPLAY INVISIBLE (-8625 650);
FORCEPROP 1 LAST HDL_POWER GND
J 1
(-8675 575);
DISPLAY 0.872340 (-8675 575);
PAINT GREEN (-8675 575);
DISPLAY INVISIBLE (-8675 575);
FORCEPROP 2 LAST CDS_LIB pure_quanta_power
J 0
(-8700 650);
DISPLAY INVISIBLE (-8700 650);
FORCEADD UNIVERSAL_GND..1
(-9625 3725);
FORCEPROP 3 LASTPIN (-9625 3775) SIG_NAME GND\g
J 0
(-9615 3785);
DISPLAY 0.659574 (-9615 3785);
PAINT MONO (-9615 3785);
DISPLAY INVISIBLE (-9615 3785);
FORCEPROP 1 LAST PATH I40
J 0
(-9550 3725);
DISPLAY 0.872340 (-9550 3725);
PAINT AQUA (-9550 3725);
DISPLAY INVISIBLE (-9550 3725);
FORCEPROP 1 LAST HDL_POWER GND
J 1
(-9600 3650);
DISPLAY 0.872340 (-9600 3650);
PAINT GREEN (-9600 3650);
DISPLAY INVISIBLE (-9600 3650);
FORCEPROP 2 LAST CDS_LIB pure_quanta_power
J 0
(-9625 3725);
DISPLAY INVISIBLE (-9625 3725);
FORCEADD OFFPAGE..2
R 2
(-9425 4350);
FORCEPROP 2 LAST $XR0 365 
J 0
(-9710 4350);
DISPLAY 0.638298 (-9710 4350);
PAINT MONO (-9710 4350);
FORCEPROP 2 LAST PATH I41
J 0
(-9375 4425);
DISPLAY 0.680851 (-9375 4425);
DISPLAY INVISIBLE (-9375 4425);
FORCEPROP 1 LAST COMMENT_BODY TRUE
J 2
(-9380 4255);
DISPLAY 1.170213 (-9380 4255);
PAINT GREEN (-9380 4255);
DISPLAY INVISIBLE (-9380 4255);
FORCEPROP 1 LAST OFFPAGE TRUE
J 2
(-9750 4225);
DISPLAY 1.170213 (-9750 4225);
PAINT GREEN (-9750 4225);
DISPLAY INVISIBLE (-9750 4225);
FORCEPROP 2 LAST CDS_LIB standard
J 0
(-9425 4350);
DISPLAY INVISIBLE (-9425 4350);
FORCEPROP 2 LAST BOM_COST VR_DIMM 
J 0
(-9706 4400);
DISPLAY 0.680851 (-9706 4400);
DISPLAY INVISIBLE (-9706 4400);
FORCEADD Q_RES..2
(-9425 6150);
FORCEPROP 1 LAST LOCATION PR6619
J 0
(-9380 6275);
DISPLAY 0.787234 (-9380 6275);
FORCEPROP 0 LAST $SEC 1
J 0
(-9375 6325);
DISPLAY 0.680851 (-9375 6325);
PAINT MONO (-9375 6325);
DISPLAY INVISIBLE (-9375 6325);
FORCEPROP 0 LAST CDS_SEC 1
J 0
(-9375 6325);
DISPLAY 0.680851 (-9375 6325);
DISPLAY INVISIBLE (-9375 6325);
FORCEPROP 1 LASTPIN (-9425 6250) $PN 1
J 0
(-9420 6212);
DISPLAY 0.787234 (-9420 6212);
PAINT MONO (-9420 6212);
FORCEPROP 1 LASTPIN (-9425 6050) $PN 2
J 0
(-9420 6060);
DISPLAY 0.787234 (-9420 6060);
PAINT MONO (-9420 6060);
FORCEPROP 1 LAST WATTAGE 1/16W
J 0
(-9385 6125);
DISPLAY 0.638298 (-9385 6125);
FORCEPROP 1 LAST MATERIAL CHIP
J 0
(-9385 6075);
DISPLAY 0.638298 (-9385 6075);
FORCEPROP 1 LAST PACK_TYPE 0402LF
J 0
(-9385 5975);
DISPLAY 0.638298 (-9385 5975);
FORCEPROP 1 LAST VALUE 0
J 0
(-9380 6225);
DISPLAY 0.638298 (-9380 6225);
FORCEPROP 1 LAST TOLERANCE 5%
J 0
(-9380 6175);
DISPLAY 0.638298 (-9380 6175);
FORCEPROP 1 LAST PATH I42
J 0
(-9375 6325);
DISPLAY 0.978723 (-9375 6325);
PAINT WHITE (-9375 6325);
DISPLAY INVISIBLE (-9375 6325);
FORCEPROP 1 LAST PART_NUMBER CS00002JB13
J 0
(-9385 6025);
DISPLAY 0.638298 (-9385 6025);
DISPLAY INVISIBLE (-9385 6025);
FORCEPROP 2 LAST CDS_LIB pure_quanta
J 0
(-9425 6150);
DISPLAY INVISIBLE (-9425 6150);
FORCEADD UNIVERSAL_POWER..1
(-9425 6450);
FORCEPROP 3 LASTPIN (-9425 6400) SIG_NAME P5V_AUX\g
J 0
(-9415 6410);
DISPLAY 0.659574 (-9415 6410);
PAINT MONO (-9415 6410);
DISPLAY INVISIBLE (-9415 6410);
FORCEPROP 1 LAST HDL_POWER P5V_AUX
J 1
(-9425 6500);
DISPLAY 0.872340 (-9425 6500);
PAINT GREEN (-9425 6500);
FORCEPROP 1 LAST PATH I43
J 0
(-9375 6475);
DISPLAY 0.872340 (-9375 6475);
PAINT AQUA (-9375 6475);
DISPLAY INVISIBLE (-9375 6475);
FORCEPROP 2 LAST CDS_LIB pure_quanta_power
J 0
(-9425 6450);
DISPLAY INVISIBLE (-9425 6450);
FORCEADD UNIVERSAL_POWER..1
(-8750 3050);
FORCEPROP 3 LASTPIN (-8750 3000) SIG_NAME P0V9_RETIMER_CPU1_PVCC\g
J 0
(-8740 3010);
DISPLAY 0.659574 (-8740 3010);
PAINT MONO (-8740 3010);
DISPLAY INVISIBLE (-8740 3010);
FORCEPROP 1 LAST HDL_POWER P0V9_RETIMER_CPU1_PVCC
J 1
(-8750 3100);
DISPLAY 0.872340 (-8750 3100);
PAINT GREEN (-8750 3100);
FORCEPROP 1 LAST PATH I44
J 0
(-8700 3075);
DISPLAY 0.872340 (-8700 3075);
PAINT AQUA (-8700 3075);
DISPLAY INVISIBLE (-8700 3075);
FORCEPROP 2 LAST CDS_LIB pure_quanta_power
J 0
(-8750 3050);
DISPLAY INVISIBLE (-8750 3050);
FORCEADD UNIVERSAL_GND..1
(-8825 3550);
FORCEPROP 3 LASTPIN (-8825 3600) SIG_NAME GND\g
J 0
(-8815 3610);
DISPLAY 0.659574 (-8815 3610);
PAINT MONO (-8815 3610);
DISPLAY INVISIBLE (-8815 3610);
FORCEPROP 1 LAST PATH I45
J 0
(-8750 3550);
DISPLAY 0.872340 (-8750 3550);
PAINT AQUA (-8750 3550);
DISPLAY INVISIBLE (-8750 3550);
FORCEPROP 1 LAST HDL_POWER GND
J 1
(-8800 3475);
DISPLAY 0.872340 (-8800 3475);
PAINT GREEN (-8800 3475);
DISPLAY INVISIBLE (-8800 3475);
FORCEPROP 2 LAST CDS_LIB pure_quanta_power
J 0
(-8825 3550);
DISPLAY INVISIBLE (-8825 3550);
FORCEADD Q_RES..2
(-8825 3800);
FORCEPROP 1 LAST LOCATION PR6622
J 0
(-8780 3925);
DISPLAY 0.978723 (-8780 3925);
FORCEPROP 0 LAST $SEC 1
J 0
(-8775 3975);
DISPLAY 0.680851 (-8775 3975);
PAINT MONO (-8775 3975);
DISPLAY INVISIBLE (-8775 3975);
FORCEPROP 0 LAST CDS_SEC 1
J 0
(-8775 3975);
DISPLAY 0.680851 (-8775 3975);
DISPLAY INVISIBLE (-8775 3975);
FORCEPROP 1 LASTPIN (-8825 3900) $PN 1
J 0
(-8820 3862);
DISPLAY 0.787234 (-8820 3862);
PAINT MONO (-8820 3862);
FORCEPROP 1 LASTPIN (-8825 3700) $PN 2
J 0
(-8820 3710);
DISPLAY 0.787234 (-8820 3710);
PAINT MONO (-8820 3710);
FORCEPROP 1 LAST PACK_TYPE 0402LF
J 0
(-8785 3625);
DISPLAY 0.510638 (-8785 3625);
FORCEPROP 1 LAST WATTAGE 1/16W
J 0
(-8785 3775);
DISPLAY 0.510638 (-8785 3775);
FORCEPROP 1 LAST VALUE 8.87K
J 0
(-8780 3875);
DISPLAY 0.510638 (-8780 3875);
FORCEPROP 1 LAST MATERIAL EMPTY
J 0
(-8785 3725);
DISPLAY 0.510638 (-8785 3725);
FORCEPROP 1 LAST TOLERANCE 1%
J 0
(-8780 3825);
DISPLAY 0.510638 (-8780 3825);
FORCEPROP 1 LAST PATH I46
J 0
(-8775 3975);
DISPLAY 0.978723 (-8775 3975);
PAINT WHITE (-8775 3975);
DISPLAY INVISIBLE (-8775 3975);
FORCEPROP 1 LAST PART_NUMBER CS28872FB01
J 0
(-8785 3675);
DISPLAY 0.510638 (-8785 3675);
DISPLAY INVISIBLE (-8785 3675);
FORCEPROP 2 LAST CDS_LIB pure_quanta
J 0
(-8825 3800);
DISPLAY INVISIBLE (-8825 3800);
FORCEADD OFFPAGE..4
R 2
(-8906 4250);
FORCEPROP 2 LASTPIN (-8856 4250) SIG_NAME PV09_RETIMER_CPU1_VCCS
J 0
(-8310 4260);
DISPLAY 0.617021 (-8310 4260);
FORCEPROP 2 LAST $XR1 366 
J 0
(-9308 4250);
DISPLAY 0.638298 (-9308 4250);
PAINT MONO (-9308 4250);
FORCEPROP 2 LAST $XR0 365 
J 0
(-9188 4250);
DISPLAY 0.638298 (-9188 4250);
PAINT MONO (-9188 4250);
FORCEPROP 2 LAST PATH I47
J 0
(-8850 4325);
DISPLAY 0.680851 (-8850 4325);
DISPLAY INVISIBLE (-8850 4325);
FORCEPROP 1 LAST COMMENT_BODY TRUE
J 2
(-8881 4150);
DISPLAY 0.872340 (-8881 4150);
PAINT GREEN (-8881 4150);
DISPLAY INVISIBLE (-8881 4150);
FORCEPROP 1 LAST OFFPAGE TRUE
J 2
(-9231 4125);
DISPLAY 0.872340 (-9231 4125);
PAINT GREEN (-9231 4125);
DISPLAY INVISIBLE (-9231 4125);
FORCEPROP 2 LAST CDS_LIB standard
J 0
(-8906 4250);
DISPLAY INVISIBLE (-8906 4250);
FORCEPROP 2 LAST BOM_COST VR_DIMM 
J 0
(-9181 4300);
DISPLAY 0.680851 (-9181 4300);
DISPLAY INVISIBLE (-9181 4300);
FORCEADD UNIVERSAL_GND..1
(-8875 4575);
FORCEPROP 3 LASTPIN (-8875 4625) SIG_NAME GND\g
J 0
(-8865 4635);
DISPLAY 0.659574 (-8865 4635);
PAINT MONO (-8865 4635);
DISPLAY INVISIBLE (-8865 4635);
FORCEPROP 1 LAST PATH I48
J 0
(-8800 4575);
DISPLAY 0.872340 (-8800 4575);
PAINT AQUA (-8800 4575);
DISPLAY INVISIBLE (-8800 4575);
FORCEPROP 1 LAST HDL_POWER GND
J 1
(-8850 4500);
DISPLAY 0.872340 (-8850 4500);
PAINT GREEN (-8850 4500);
DISPLAY INVISIBLE (-8850 4500);
FORCEPROP 2 LAST CDS_LIB pure_quanta_power
J 0
(-8875 4575);
DISPLAY INVISIBLE (-8875 4575);
FORCEADD OFFPAGE..2
R 2
(-8375 3850);
FORCEPROP 2 LAST $XR1 365 
J 0
(-8630 3814);
DISPLAY 0.638298 (-8630 3814);
PAINT MONO (-8630 3814);
FORCEPROP 2 LAST $XR0 366 
J 0
(-8630 3850);
DISPLAY 0.638298 (-8630 3850);
PAINT MONO (-8630 3850);
FORCEPROP 2 LAST PATH I49
J 0
(-8325 3925);
DISPLAY 0.680851 (-8325 3925);
DISPLAY INVISIBLE (-8325 3925);
FORCEPROP 1 LAST COMMENT_BODY TRUE
J 2
(-8330 3755);
DISPLAY 1.170213 (-8330 3755);
PAINT GREEN (-8330 3755);
DISPLAY INVISIBLE (-8330 3755);
FORCEPROP 1 LAST OFFPAGE TRUE
J 2
(-8700 3725);
DISPLAY 1.170213 (-8700 3725);
PAINT GREEN (-8700 3725);
DISPLAY INVISIBLE (-8700 3725);
FORCEPROP 2 LAST CDS_LIB standard
J 0
(-8375 3850);
DISPLAY INVISIBLE (-8375 3850);
FORCEPROP 2 LAST BOM_COST VR_DIMM 
J 0
(-8656 3900);
DISPLAY 0.680851 (-8656 3900);
DISPLAY INVISIBLE (-8656 3900);
FORCEADD Q_RES..2
(-8700 900);
FORCEPROP 1 LAST LOCATION PR6628
J 0
(-8655 1025);
DISPLAY 0.978723 (-8655 1025);
FORCEPROP 0 LAST $SEC 1
J 0
(-8650 1075);
DISPLAY 0.680851 (-8650 1075);
PAINT MONO (-8650 1075);
DISPLAY INVISIBLE (-8650 1075);
FORCEPROP 0 LAST CDS_SEC 1
J 0
(-8650 1075);
DISPLAY 0.680851 (-8650 1075);
DISPLAY INVISIBLE (-8650 1075);
FORCEPROP 1 LASTPIN (-8700 1000) $PN 1
J 0
(-8695 962);
DISPLAY 0.787234 (-8695 962);
PAINT MONO (-8695 962);
FORCEPROP 1 LASTPIN (-8700 800) $PN 2
J 0
(-8695 810);
DISPLAY 0.787234 (-8695 810);
PAINT MONO (-8695 810);
FORCEPROP 1 LAST WATTAGE 1/16W
J 0
(-8660 875);
DISPLAY 0.510638 (-8660 875);
FORCEPROP 1 LAST TOLERANCE 1%
J 0
(-8655 925);
DISPLAY 0.510638 (-8655 925);
FORCEPROP 1 LAST VALUE 8.87K
J 0
(-8655 975);
DISPLAY 0.510638 (-8655 975);
FORCEPROP 1 LAST MATERIAL EMPTY
J 0
(-8660 825);
DISPLAY 0.510638 (-8660 825);
FORCEPROP 1 LAST PACK_TYPE 0402LF
J 0
(-8660 725);
DISPLAY 0.510638 (-8660 725);
FORCEPROP 1 LAST PATH I5
J 0
(-8650 1075);
DISPLAY 0.978723 (-8650 1075);
PAINT WHITE (-8650 1075);
DISPLAY INVISIBLE (-8650 1075);
FORCEPROP 1 LAST PART_NUMBER CS28872FB01
J 0
(-8660 775);
DISPLAY 0.510638 (-8660 775);
DISPLAY INVISIBLE (-8660 775);
FORCEPROP 2 LAST CDS_LIB pure_quanta
J 0
(-8700 900);
DISPLAY INVISIBLE (-8700 900);
FORCEADD OFFPAGE..4
R 2
(-8350 3750);
FORCEPROP 2 LASTPIN (-8300 3750) SIG_NAME P0V9_RETIMER_CPU1_PWM1
J 0
(-8310 3760);
DISPLAY 0.617021 (-8310 3760);
FORCEPROP 2 LAST $XR0 365 
J 0
(-8602 3750);
DISPLAY 0.638298 (-8602 3750);
PAINT MONO (-8602 3750);
FORCEPROP 2 LAST PATH I50
J 0
(-8300 3825);
DISPLAY 0.680851 (-8300 3825);
DISPLAY INVISIBLE (-8300 3825);
FORCEPROP 1 LAST COMMENT_BODY TRUE
J 2
(-8325 3650);
DISPLAY 0.872340 (-8325 3650);
PAINT GREEN (-8325 3650);
DISPLAY INVISIBLE (-8325 3650);
FORCEPROP 1 LAST OFFPAGE TRUE
J 2
(-8675 3625);
DISPLAY 0.872340 (-8675 3625);
PAINT GREEN (-8675 3625);
DISPLAY INVISIBLE (-8675 3625);
FORCEPROP 2 LAST CDS_LIB standard
J 0
(-8350 3750);
DISPLAY INVISIBLE (-8350 3750);
FORCEPROP 2 LAST BOM_COST VR_DIMM 
J 0
(-8645 3800);
DISPLAY 0.680851 (-8645 3800);
DISPLAY INVISIBLE (-8645 3800);
FORCEADD ISL99390FRZTR5935..1
(-7075 4350);
FORCEPROP 1 LAST LOCATION PU6511
J 0
(-7375 5225);
DISPLAY 0.723404 (-7375 5225);
PAINT GREEN (-7375 5225);
FORCEPROP 2 LAST SEC 1
J 0
(-7375 5450);
DISPLAY 0.680851 (-7375 5450);
PAINT MONO (-7375 5450);
DISPLAY INVISIBLE (-7375 5450);
FORCEPROP 2 LASTPIN (-6675 3900) $PN 2
J 0
(-6665 3910);
DISPLAY 0.680851 (-6665 3910);
PAINT MONO (-6665 3910);
FORCEPROP 2 LASTPIN (-6675 4700) $PN 33
J 0
(-6665 4710);
DISPLAY 0.680851 (-6665 4710);
PAINT MONO (-6665 4710);
FORCEPROP 2 LASTPIN (-7525 4100) $PN 31
J 2
(-7535 4110);
DISPLAY 0.680851 (-7535 4110);
PAINT MONO (-7535 4110);
FORCEPROP 2 LASTPIN (-7525 4500) $PN 35
J 2
(-7535 4510);
DISPLAY 0.680851 (-7535 4510);
PAINT MONO (-7535 4510);
FORCEPROP 2 LASTPIN (-6675 4050) $PN 6
J 0
(-6665 4060);
DISPLAY 0.680851 (-6665 4060);
PAINT MONO (-6665 4060);
FORCEPROP 2 LASTPIN (-6675 4000) $PN 41
J 0
(-6665 4010);
DISPLAY 0.680851 (-6665 4010);
PAINT MONO (-6665 4010);
FORCEPROP 2 LASTPIN (-7525 4350) $PN 38
J 2
(-7535 4360);
DISPLAY 0.680851 (-7535 4360);
PAINT MONO (-7535 4360);
FORCEPROP 2 LASTPIN (-7525 4050) $PN 37
J 2
(-7535 4060);
DISPLAY 0.680851 (-7535 4060);
PAINT MONO (-7535 4060);
FORCEPROP 2 LASTPIN (-6675 3850) $PN 5
J 0
(-6665 3860);
DISPLAY 0.680851 (-6665 3860);
PAINT MONO (-6665 3860);
FORCEPROP 2 LASTPIN (-6675 3800) $PN 7_9-20_24
J 0
(-6665 3810);
DISPLAY 0.680851 (-6665 3810);
PAINT MONO (-6665 3810);
FORCEPROP 2 LASTPIN (-6675 3750) $PN 40
J 0
(-6665 3760);
DISPLAY 0.680851 (-6665 3760);
PAINT MONO (-6665 3760);
FORCEPROP 2 LASTPIN (-6675 4450) $PN 32
J 0
(-6665 4460);
DISPLAY 0.680851 (-6665 4460);
PAINT MONO (-6665 4460);
FORCEPROP 2 LASTPIN (-7525 5000) $PN 4
J 2
(-7535 5010);
DISPLAY 0.680851 (-7535 5010);
PAINT MONO (-7535 5010);
FORCEPROP 2 LASTPIN (-7525 3750) $PN 34
J 2
(-7535 3760);
DISPLAY 0.680851 (-7535 3760);
PAINT MONO (-7535 3760);
FORCEPROP 2 LASTPIN (-7525 4250) $PN 39
J 2
(-7535 4260);
DISPLAY 0.680851 (-7535 4260);
PAINT MONO (-7535 4260);
FORCEPROP 2 LASTPIN (-6675 4350) $PN 10_19
J 0
(-6665 4360);
DISPLAY 0.680851 (-6665 4360);
PAINT MONO (-6665 4360);
FORCEPROP 2 LASTPIN (-7525 3850) $PN 36
J 2
(-7535 3860);
DISPLAY 0.680851 (-7535 3860);
PAINT MONO (-7535 3860);
FORCEPROP 2 LASTPIN (-7525 4700) $PN 3
J 2
(-7535 4710);
DISPLAY 0.680851 (-7535 4710);
PAINT MONO (-7535 4710);
FORCEPROP 2 LASTPIN (-6675 5000) $PN 25_29
J 0
(-6665 5010);
DISPLAY 0.680851 (-6665 5010);
PAINT MONO (-6665 5010);
FORCEPROP 2 LASTPIN (-6675 4950) $PN 30
J 0
(-6665 4960);
DISPLAY 0.680851 (-6665 4960);
PAINT MONO (-6665 4960);
FORCEPROP 2 LASTPIN (-6675 4100) $PN 1
J 0
(-6665 4110);
DISPLAY 0.680851 (-6665 4110);
PAINT MONO (-6665 4110);
FORCEPROP 2 LAST VALUE ISL99390FRZ-TR5935
J 0
(-7375 5325);
DISPLAY 0.617021 (-7375 5325);
FORCEPROP 1 LAST MATERIAL IC
J 0
(-7375 5075);
DISPLAY 0.723404 (-7375 5075);
PAINT GREEN (-7375 5075);
FORCEPROP 2 LAST PART_TYPE SMLF
J 0
(-7375 5400);
DISPLAY 0.680851 (-7375 5400);
FORCEPROP 1 LAST PATH I51
J 0
(-7075 4350);
DISPLAY 0.723404 (-7075 4350);
PAINT GREEN (-7075 4350);
DISPLAY INVISIBLE (-7075 4350);
FORCEPROP 1 LAST PART_NUMBER AL099390004
J 0
(-7375 5150);
DISPLAY 0.723404 (-7375 5150);
PAINT GREEN (-7375 5150);
DISPLAY INVISIBLE (-7375 5150);
FORCEPROP 2 LAST SEC_TYPE 
J 0
(-7375 5450);
DISPLAY 0.680851 (-7375 5450);
DISPLAY INVISIBLE (-7375 5450);
FORCEPROP 2 LAST CDS_LIB pure_quanta
J 0
(-7075 4350);
DISPLAY INVISIBLE (-7075 4350);
FORCEPROP 1 LAST CDS_LMAN_SYM_OUTLINE -300,700,250,-650
J 0
(-7075 4350);
DISPLAY 0.468085 (-7075 4350);
PAINT GREEN (-7075 4350);
DISPLAY INVISIBLE (-7075 4350);
FORCEPROP 1 LAST NEEDS_NO_SIZE TRUE
J 0
(-7075 4350);
DISPLAY 0.723404 (-7075 4350);
PAINT GREEN (-7075 4350);
DISPLAY INVISIBLE (-7075 4350);
FORCEPROP 2 LAST BOM_COST VR_DIMM 
J 0
(-7350 5375);
DISPLAY 0.680851 (-7350 5375);
DISPLAY INVISIBLE (-7350 5375);
FORCEADD Q_CAP..1
(-8875 4775);
FORCEPROP 1 LAST LOCATION PC6610
J 0
(-8825 4875);
DISPLAY 0.978723 (-8825 4875);
FORCEPROP 0 LAST $SEC 1
J 0
(-8825 4925);
DISPLAY 0.680851 (-8825 4925);
PAINT MONO (-8825 4925);
DISPLAY INVISIBLE (-8825 4925);
FORCEPROP 0 LAST CDS_SEC 1
J 0
(-8825 4925);
DISPLAY 0.680851 (-8825 4925);
DISPLAY INVISIBLE (-8825 4925);
FORCEPROP 1 LASTPIN (-8875 4875) $PN 1
J 0
(-8865 4855);
DISPLAY 0.787234 (-8865 4855);
PAINT MONO (-8865 4855);
FORCEPROP 1 LASTPIN (-8875 4675) $PN 2
J 0
(-8865 4655);
DISPLAY 0.787234 (-8865 4655);
PAINT MONO (-8865 4655);
FORCEPROP 1 LAST PACK_TYPE C0402
J 0
(-8825 4625);
DISPLAY 0.617021 (-8825 4625);
FORCEPROP 1 LAST MATERIAL X6S
J 0
(-8825 4725);
DISPLAY 0.617021 (-8825 4725);
FORCEPROP 1 LAST VOLTAGE 10V
J 0
(-8825 4775);
DISPLAY 0.617021 (-8825 4775);
FORCEPROP 1 LAST VALUE 2.2UF
J 0
(-8825 4825);
DISPLAY 0.617021 (-8825 4825);
FORCEPROP 1 LAST PATH I52
J 0
(-8825 4925);
DISPLAY 0.978723 (-8825 4925);
PAINT WHITE (-8825 4925);
DISPLAY INVISIBLE (-8825 4925);
FORCEPROP 1 LAST PART_NUMBER CH5222KEB01
J 0
(-8825 4675);
DISPLAY 0.617021 (-8825 4675);
DISPLAY INVISIBLE (-8825 4675);
FORCEPROP 2 LAST CDS_LIB pure_quanta
J 0
(-8875 4775);
DISPLAY INVISIBLE (-8875 4775);
FORCEPROP 1 LAST TOLERANCE 10%
J 0
(-8825 4725);
DISPLAY 0.978723 (-8825 4725);
PAINT SKYBLUE (-8825 4725);
DISPLAY INVISIBLE (-8825 4725);
FORCEPROP 2 LAST BOM_COST VR_DIMM 
J 0
(-8825 4925);
DISPLAY 0.680851 (-8825 4925);
DISPLAY INVISIBLE (-8825 4925);
FORCEADD Q_RES..2
(-8875 5300);
FORCEPROP 1 LAST LOCATION PR6621
J 0
(-8830 5425);
DISPLAY 0.723404 (-8830 5425);
FORCEPROP 0 LAST $SEC 1
J 0
(-8825 5475);
DISPLAY 0.680851 (-8825 5475);
PAINT MONO (-8825 5475);
DISPLAY INVISIBLE (-8825 5475);
FORCEPROP 0 LAST CDS_SEC 1
J 0
(-8825 5475);
DISPLAY 0.680851 (-8825 5475);
DISPLAY INVISIBLE (-8825 5475);
FORCEPROP 1 LASTPIN (-8875 5400) $PN 1
J 0
(-8870 5362);
DISPLAY 0.787234 (-8870 5362);
PAINT MONO (-8870 5362);
FORCEPROP 1 LASTPIN (-8875 5200) $PN 2
J 0
(-8870 5210);
DISPLAY 0.787234 (-8870 5210);
PAINT MONO (-8870 5210);
FORCEPROP 1 LAST WATTAGE 1/16W
J 0
(-8835 5275);
DISPLAY 0.617021 (-8835 5275);
FORCEPROP 1 LAST VALUE 2.2
J 0
(-8830 5375);
DISPLAY 0.617021 (-8830 5375);
FORCEPROP 1 LAST TOLERANCE 5%
J 0
(-8830 5325);
DISPLAY 0.617021 (-8830 5325);
FORCEPROP 1 LAST MATERIAL CHIP
J 0
(-8835 5225);
DISPLAY 0.617021 (-8835 5225);
FORCEPROP 1 LAST PACK_TYPE 0402LF
J 0
(-8835 5125);
DISPLAY 0.617021 (-8835 5125);
FORCEPROP 1 LAST PATH I53
J 0
(-8825 5475);
DISPLAY 0.978723 (-8825 5475);
PAINT WHITE (-8825 5475);
DISPLAY INVISIBLE (-8825 5475);
FORCEPROP 1 LAST PART_NUMBER TMP_QCS-2202JB25
J 0
(-8850 5175);
DISPLAY 0.617021 (-8850 5175);
DISPLAY INVISIBLE (-8850 5175);
FORCEPROP 2 LAST CDS_LIB pure_quanta
J 0
(-8875 5300);
DISPLAY INVISIBLE (-8875 5300);
FORCEPROP 2 LAST BOM_COST VR_DIMM 
J 0
(-8825 5475);
DISPLAY 0.680851 (-8825 5475);
DISPLAY INVISIBLE (-8825 5475);
FORCEADD UNIVERSAL_GND..1
(-8175 5050);
FORCEPROP 3 LASTPIN (-8175 5100) SIG_NAME GND\g
J 0
(-8165 5110);
DISPLAY 0.659574 (-8165 5110);
PAINT MONO (-8165 5110);
DISPLAY INVISIBLE (-8165 5110);
FORCEPROP 1 LAST PATH I54
J 0
(-8100 5050);
DISPLAY 0.872340 (-8100 5050);
PAINT AQUA (-8100 5050);
DISPLAY INVISIBLE (-8100 5050);
FORCEPROP 1 LAST HDL_POWER GND
J 1
(-8150 4975);
DISPLAY 0.872340 (-8150 4975);
PAINT GREEN (-8150 4975);
DISPLAY INVISIBLE (-8150 4975);
FORCEPROP 2 LAST CDS_LIB pure_quanta_power
J 0
(-8175 5050);
DISPLAY INVISIBLE (-8175 5050);
FORCEADD Q_CAP..1
(-8175 5300);
FORCEPROP 1 LAST LOCATION PC6609_09P1_1
J 0
(-8125 5400);
DISPLAY 0.978723 (-8125 5400);
FORCEPROP 0 LAST $SEC 1
J 0
(-8125 5450);
DISPLAY 0.680851 (-8125 5450);
PAINT MONO (-8125 5450);
DISPLAY INVISIBLE (-8125 5450);
FORCEPROP 0 LAST CDS_SEC 1
J 0
(-8125 5450);
DISPLAY 0.680851 (-8125 5450);
DISPLAY INVISIBLE (-8125 5450);
FORCEPROP 1 LASTPIN (-8175 5400) $PN 1
J 0
(-8165 5380);
DISPLAY 0.787234 (-8165 5380);
PAINT MONO (-8165 5380);
FORCEPROP 1 LASTPIN (-8175 5200) $PN 2
J 0
(-8165 5180);
DISPLAY 0.787234 (-8165 5180);
PAINT MONO (-8165 5180);
FORCEPROP 1 LAST VOLTAGE 10V
J 0
(-8125 5300);
DISPLAY 0.617021 (-8125 5300);
FORCEPROP 1 LAST VALUE 2.2UF
J 0
(-8125 5350);
DISPLAY 0.617021 (-8125 5350);
FORCEPROP 1 LAST TOLERANCE 10%
J 0
(-8125 5250);
DISPLAY 0.617021 (-8125 5250);
FORCEPROP 1 LAST PACK_TYPE C0402
J 0
(-8125 5100);
DISPLAY 0.617021 (-8125 5100);
FORCEPROP 1 LAST MATERIAL X6S
J 0
(-8125 5200);
DISPLAY 0.617021 (-8125 5200);
FORCEPROP 1 LAST PATH I55
J 0
(-8125 5450);
DISPLAY 0.978723 (-8125 5450);
PAINT WHITE (-8125 5450);
DISPLAY INVISIBLE (-8125 5450);
FORCEPROP 1 LAST PART_NUMBER CH5222KEB01
J 0
(-8125 5150);
DISPLAY 0.617021 (-8125 5150);
DISPLAY INVISIBLE (-8125 5150);
FORCEPROP 2 LAST CDS_LIB pure_quanta
J 0
(-8175 5300);
DISPLAY INVISIBLE (-8175 5300);
FORCEPROP 2 LAST BOM_COST VR_DIMM 
J 0
(-8125 5450);
DISPLAY 0.680851 (-8125 5450);
DISPLAY INVISIBLE (-8125 5450);
FORCEADD Q_RES..2
(-8525 6150);
FORCEPROP 1 LAST LOCATION PR6620
J 0
(-8480 6275);
DISPLAY 0.787234 (-8480 6275);
FORCEPROP 0 LAST $SEC 1
J 0
(-8475 6325);
DISPLAY 0.680851 (-8475 6325);
PAINT MONO (-8475 6325);
DISPLAY INVISIBLE (-8475 6325);
FORCEPROP 0 LAST CDS_SEC 1
J 0
(-8475 6325);
DISPLAY 0.680851 (-8475 6325);
DISPLAY INVISIBLE (-8475 6325);
FORCEPROP 1 LASTPIN (-8525 6250) $PN 1
J 0
(-8520 6212);
DISPLAY 0.787234 (-8520 6212);
PAINT MONO (-8520 6212);
FORCEPROP 1 LASTPIN (-8525 6050) $PN 2
J 0
(-8520 6060);
DISPLAY 0.787234 (-8520 6060);
PAINT MONO (-8520 6060);
FORCEPROP 1 LAST VALUE 0
J 0
(-8480 6225);
DISPLAY 0.510638 (-8480 6225);
FORCEPROP 1 LAST TOLERANCE 5%
J 0
(-8480 6175);
DISPLAY 0.510638 (-8480 6175);
FORCEPROP 1 LAST WATTAGE 1/16W
J 0
(-8485 6125);
DISPLAY 0.510638 (-8485 6125);
FORCEPROP 1 LAST MATERIAL EMPTY
J 0
(-8485 6075);
DISPLAY 0.510638 (-8485 6075);
PAINT RED (-8485 6075);
FORCEPROP 1 LAST PACK_TYPE 0402LF
J 0
(-8485 5975);
DISPLAY 0.510638 (-8485 5975);
FORCEPROP 1 LAST PATH I56
J 0
(-8475 6325);
DISPLAY 0.978723 (-8475 6325);
PAINT WHITE (-8475 6325);
DISPLAY INVISIBLE (-8475 6325);
FORCEPROP 1 LAST PART_NUMBER CS00002JB13
J 0
(-8485 6025);
DISPLAY 0.510638 (-8485 6025);
DISPLAY INVISIBLE (-8485 6025);
FORCEPROP 2 LAST CDS_LIB pure_quanta
J 0
(-8525 6150);
DISPLAY INVISIBLE (-8525 6150);
FORCEADD UNIVERSAL_POWER..1
(-8525 6450);
FORCEPROP 3 LASTPIN (-8525 6400) SIG_NAME P3V3_AUX\g
J 0
(-8515 6410);
DISPLAY 0.659574 (-8515 6410);
PAINT MONO (-8515 6410);
DISPLAY INVISIBLE (-8515 6410);
FORCEPROP 1 LAST HDL_POWER P3V3_AUX
J 1
(-8525 6500);
DISPLAY 0.872340 (-8525 6500);
PAINT GREEN (-8525 6500);
FORCEPROP 1 LAST PATH I57
J 0
(-8475 6475);
DISPLAY 0.872340 (-8475 6475);
PAINT AQUA (-8475 6475);
DISPLAY INVISIBLE (-8475 6475);
FORCEPROP 2 LAST CDS_LIB pure_quanta_power
J 0
(-8525 6450);
DISPLAY INVISIBLE (-8525 6450);
FORCEADD UNIVERSAL_GND..1
(-6500 3550);
FORCEPROP 3 LASTPIN (-6500 3600) SIG_NAME GND\g
J 0
(-6490 3610);
DISPLAY 0.659574 (-6490 3610);
PAINT MONO (-6490 3610);
DISPLAY INVISIBLE (-6490 3610);
FORCEPROP 1 LAST PATH I58
J 0
(-6425 3550);
DISPLAY 0.872340 (-6425 3550);
PAINT AQUA (-6425 3550);
DISPLAY INVISIBLE (-6425 3550);
FORCEPROP 1 LAST HDL_POWER GND
J 1
(-6475 3475);
DISPLAY 0.872340 (-6475 3475);
PAINT GREEN (-6475 3475);
DISPLAY INVISIBLE (-6475 3475);
FORCEPROP 2 LAST CDS_LIB pure_quanta_power
J 0
(-6500 3550);
DISPLAY INVISIBLE (-6500 3550);
FORCEADD Q_RES..1
(-5100 3200);
FORCEPROP 1 LAST LOCATION PR6626
J 0
(-5200 3125);
DISPLAY 0.978723 (-5200 3125);
FORCEPROP 0 LAST $SEC 1
J 0
(-4950 3375);
DISPLAY 0.680851 (-4950 3375);
PAINT MONO (-4950 3375);
DISPLAY INVISIBLE (-4950 3375);
FORCEPROP 0 LAST CDS_SEC 1
J 0
(-4950 3375);
DISPLAY 0.680851 (-4950 3375);
DISPLAY INVISIBLE (-4950 3375);
FORCEPROP 1 LASTPIN (-5200 3200) $PN 1
J 0
(-5188 3212);
DISPLAY 0.787234 (-5188 3212);
PAINT MONO (-5188 3212);
FORCEPROP 1 LASTPIN (-5000 3200) $PN 2
J 0
(-5038 3212);
DISPLAY 0.787234 (-5038 3212);
PAINT MONO (-5038 3212);
FORCEPROP 1 LAST VALUE 0
J 2
(-4925 3200);
DISPLAY 0.617021 (-4925 3200);
FORCEPROP 1 LAST TOLERANCE 5%
J 0
(-4875 3200);
DISPLAY 0.617021 (-4875 3200);
FORCEPROP 1 LAST PACK_TYPE 0402LF
J 0
(-4950 3325);
DISPLAY 0.617021 (-4950 3325);
FORCEPROP 1 LAST WATTAGE 1/16W
J 2
(-5000 3325);
DISPLAY 0.617021 (-5000 3325);
FORCEPROP 1 LAST MATERIAL CHIP
J 0
(-5300 3325);
DISPLAY 0.617021 (-5300 3325);
FORCEPROP 1 LAST PATH I59
J 0
(-5150 3350);
DISPLAY 0.978723 (-5150 3350);
PAINT WHITE (-5150 3350);
DISPLAY INVISIBLE (-5150 3350);
FORCEPROP 1 LAST PART_NUMBER CS00002JB13
J 0
(-5300 3275);
DISPLAY 0.617021 (-5300 3275);
DISPLAY INVISIBLE (-5300 3275);
FORCEPROP 2 LAST BOM_COST VR_DIMM 
J 0
(-5150 3175);
DISPLAY 0.680851 (-5150 3175);
DISPLAY INVISIBLE (-5150 3175);
FORCEPROP 2 LAST CDS_LIB pure_quanta
J 0
(-5100 3200);
DISPLAY INVISIBLE (-5100 3200);
FORCEADD OFFPAGE..4
R 2
(-8781 1350);
FORCEPROP 2 LAST $XR1 366 
J 0
(-9153 1350);
DISPLAY 0.638298 (-9153 1350);
PAINT MONO (-9153 1350);
FORCEPROP 2 LAST $XR0 365 
J 0
(-9033 1350);
DISPLAY 0.638298 (-9033 1350);
PAINT MONO (-9033 1350);
FORCEPROP 2 LAST PATH I6
J 0
(-8725 1425);
DISPLAY 0.680851 (-8725 1425);
DISPLAY INVISIBLE (-8725 1425);
FORCEPROP 1 LAST COMMENT_BODY TRUE
J 2
(-8756 1250);
DISPLAY 0.872340 (-8756 1250);
PAINT GREEN (-8756 1250);
DISPLAY INVISIBLE (-8756 1250);
FORCEPROP 1 LAST OFFPAGE TRUE
J 2
(-9106 1225);
DISPLAY 0.872340 (-9106 1225);
PAINT GREEN (-9106 1225);
DISPLAY INVISIBLE (-9106 1225);
FORCEPROP 2 LAST CDS_LIB standard
J 0
(-8781 1350);
DISPLAY INVISIBLE (-8781 1350);
FORCEPROP 2 LAST BOM_COST VR_DIMM 
J 0
(-9056 1400);
DISPLAY 0.680851 (-9056 1400);
DISPLAY INVISIBLE (-9056 1400);
FORCEADD UNIVERSAL_GND..1
(-5975 4875);
FORCEPROP 3 LASTPIN (-5975 4925) SIG_NAME GND\g
J 0
(-5965 4935);
DISPLAY 0.659574 (-5965 4935);
PAINT MONO (-5965 4935);
DISPLAY INVISIBLE (-5965 4935);
FORCEPROP 1 LAST PATH I60
J 0
(-5900 4875);
DISPLAY 0.872340 (-5900 4875);
PAINT AQUA (-5900 4875);
DISPLAY INVISIBLE (-5900 4875);
FORCEPROP 1 LAST HDL_POWER GND
J 1
(-5950 4800);
DISPLAY 0.872340 (-5950 4800);
PAINT GREEN (-5950 4800);
DISPLAY INVISIBLE (-5950 4800);
FORCEPROP 2 LAST CDS_LIB pure_quanta_power
J 0
(-5975 4875);
DISPLAY INVISIBLE (-5975 4875);
FORCEADD Q_CAP..1
(-5975 5150);
FORCEPROP 1 LAST LOCATION PC6613_1
J 0
(-5925 5250);
DISPLAY 0.978723 (-5925 5250);
FORCEPROP 0 LAST $SEC 1
J 0
(-5925 5300);
DISPLAY 0.680851 (-5925 5300);
PAINT MONO (-5925 5300);
DISPLAY INVISIBLE (-5925 5300);
FORCEPROP 0 LAST CDS_SEC 1
J 0
(-5925 5300);
DISPLAY 0.680851 (-5925 5300);
DISPLAY INVISIBLE (-5925 5300);
FORCEPROP 1 LASTPIN (-5975 5250) $PN 1
J 0
(-5965 5230);
DISPLAY 0.787234 (-5965 5230);
PAINT MONO (-5965 5230);
FORCEPROP 1 LASTPIN (-5975 5050) $PN 2
J 0
(-5965 5030);
DISPLAY 0.787234 (-5965 5030);
PAINT MONO (-5965 5030);
FORCEPROP 1 LAST PACK_TYPE 0402
J 0
(-5925 4950);
DISPLAY 0.617021 (-5925 4950);
FORCEPROP 1 LAST TOLERANCE 10%
J 0
(-5925 5100);
DISPLAY 0.617021 (-5925 5100);
FORCEPROP 1 LAST MATERIAL X7R
J 0
(-5925 5050);
DISPLAY 0.617021 (-5925 5050);
FORCEPROP 1 LAST VOLTAGE 50V
J 0
(-5925 5150);
DISPLAY 0.617021 (-5925 5150);
FORCEPROP 1 LAST VALUE 3300PF
J 0
(-5925 5200);
DISPLAY 0.617021 (-5925 5200);
FORCEPROP 1 LAST PATH I61
J 0
(-5925 5300);
DISPLAY 0.978723 (-5925 5300);
PAINT WHITE (-5925 5300);
DISPLAY INVISIBLE (-5925 5300);
FORCEPROP 1 LAST PART_NUMBER TMP_QCH2336K1B12
J 0
(-5925 5000);
DISPLAY 0.617021 (-5925 5000);
DISPLAY INVISIBLE (-5925 5000);
FORCEPROP 2 LAST CDS_LIB pure_quanta
J 0
(-5975 5150);
DISPLAY INVISIBLE (-5975 5150);
FORCEPROP 2 LAST BOM_COST VR_DIMM 
J 0
(-5925 5300);
DISPLAY 0.680851 (-5925 5300);
DISPLAY INVISIBLE (-5925 5300);
FORCEADD Q_RES..1
(-5475 4700);
FORCEPROP 1 LAST LOCATION PR6623
J 0
(-5700 4700);
DISPLAY 0.638298 (-5700 4700);
FORCEPROP 0 LAST $SEC 1
J 0
(-5350 4850);
DISPLAY 0.680851 (-5350 4850);
PAINT MONO (-5350 4850);
DISPLAY INVISIBLE (-5350 4850);
FORCEPROP 0 LAST CDS_SEC 1
J 0
(-5350 4850);
DISPLAY 0.680851 (-5350 4850);
DISPLAY INVISIBLE (-5350 4850);
FORCEPROP 1 LASTPIN (-5575 4700) $PN 1
J 0
(-5563 4712);
DISPLAY 0.787234 (-5563 4712);
PAINT MONO (-5563 4712);
FORCEPROP 1 LASTPIN (-5375 4700) $PN 2
J 0
(-5413 4712);
DISPLAY 0.787234 (-5413 4712);
PAINT MONO (-5413 4712);
FORCEPROP 1 LAST VALUE 5.6
J 2
(-5300 4700);
DISPLAY 0.510638 (-5300 4700);
FORCEPROP 1 LAST MATERIAL CHIP
J 0
(-5625 4825);
DISPLAY 0.510638 (-5625 4825);
FORCEPROP 1 LAST PACK_TYPE 0402LF
J 0
(-5350 4825);
DISPLAY 0.510638 (-5350 4825);
FORCEPROP 1 LAST WATTAGE 1/16W
J 2
(-5375 4825);
DISPLAY 0.510638 (-5375 4825);
FORCEPROP 1 LAST TOLERANCE 1%
J 0
(-5275 4700);
DISPLAY 0.510638 (-5275 4700);
FORCEPROP 1 LAST PATH I62
J 0
(-5525 4850);
DISPLAY 0.978723 (-5525 4850);
PAINT WHITE (-5525 4850);
DISPLAY INVISIBLE (-5525 4850);
FORCEPROP 1 LAST PART_NUMBER CS-5602FB01
J 0
(-5625 4775);
DISPLAY 0.510638 (-5625 4775);
DISPLAY INVISIBLE (-5625 4775);
FORCEPROP 2 LAST CDS_LIB pure_quanta
J 0
(-5475 4700);
DISPLAY INVISIBLE (-5475 4700);
FORCEADD UNIVERSAL_GND..1
(-5475 4875);
FORCEPROP 3 LASTPIN (-5475 4925) SIG_NAME GND\g
J 0
(-5465 4935);
DISPLAY 0.659574 (-5465 4935);
PAINT MONO (-5465 4935);
DISPLAY INVISIBLE (-5465 4935);
FORCEPROP 1 LAST PATH I63
J 0
(-5400 4875);
DISPLAY 0.872340 (-5400 4875);
PAINT AQUA (-5400 4875);
DISPLAY INVISIBLE (-5400 4875);
FORCEPROP 1 LAST HDL_POWER GND
J 1
(-5450 4800);
DISPLAY 0.872340 (-5450 4800);
PAINT GREEN (-5450 4800);
DISPLAY INVISIBLE (-5450 4800);
FORCEPROP 2 LAST CDS_LIB pure_quanta_power
J 0
(-5475 4875);
DISPLAY INVISIBLE (-5475 4875);
FORCEADD Q_CAP..1
(-5475 5150);
FORCEPROP 1 LAST LOCATION PC6612_1
J 0
(-5425 5250);
DISPLAY 0.978723 (-5425 5250);
FORCEPROP 0 LAST $SEC 1
J 0
(-5425 5300);
DISPLAY 0.680851 (-5425 5300);
PAINT MONO (-5425 5300);
DISPLAY INVISIBLE (-5425 5300);
FORCEPROP 0 LAST CDS_SEC 1
J 0
(-5425 5300);
DISPLAY 0.680851 (-5425 5300);
DISPLAY INVISIBLE (-5425 5300);
FORCEPROP 1 LASTPIN (-5475 5250) $PN 1
J 0
(-5465 5230);
DISPLAY 0.787234 (-5465 5230);
PAINT MONO (-5465 5230);
FORCEPROP 1 LASTPIN (-5475 5050) $PN 2
J 0
(-5465 5030);
DISPLAY 0.787234 (-5465 5030);
PAINT MONO (-5465 5030);
FORCEPROP 1 LAST PACK_TYPE C0402
J 0
(-5425 4950);
DISPLAY 0.617021 (-5425 4950);
FORCEPROP 1 LAST VOLTAGE 25V
J 0
(-5425 5150);
DISPLAY 0.617021 (-5425 5150);
FORCEPROP 1 LAST TOLERANCE 10%
J 0
(-5425 5100);
DISPLAY 0.617021 (-5425 5100);
FORCEPROP 1 LAST VALUE 1UF
J 0
(-5425 5200);
DISPLAY 0.617021 (-5425 5200);
FORCEPROP 1 LAST MATERIAL X6S
J 0
(-5425 5050);
DISPLAY 0.617021 (-5425 5050);
FORCEPROP 1 LAST PATH I64
J 0
(-5425 5300);
DISPLAY 0.978723 (-5425 5300);
PAINT WHITE (-5425 5300);
DISPLAY INVISIBLE (-5425 5300);
FORCEPROP 1 LAST PART_NUMBER CH5104KEB02
J 0
(-5425 5000);
DISPLAY 0.617021 (-5425 5000);
DISPLAY INVISIBLE (-5425 5000);
FORCEPROP 2 LAST CDS_LIB pure_quanta
J 0
(-5475 5150);
DISPLAY INVISIBLE (-5475 5150);
FORCEPROP 2 LAST BOM_COST VR_DIMM 
J 0
(-5425 5300);
DISPLAY 0.680851 (-5425 5300);
DISPLAY INVISIBLE (-5425 5300);
FORCEADD Q_INDUCTOR..1
(-4900 4375);
FORCEPROP 1 LAST LOCATION PL6511
J 0
(-5175 4400);
DISPLAY 0.723404 (-5175 4400);
PAINT GREEN (-5175 4400);
FORCEPROP 0 LAST $SEC 1
J 0
(-5175 4450);
DISPLAY 0.680851 (-5175 4450);
PAINT MONO (-5175 4450);
DISPLAY INVISIBLE (-5175 4450);
FORCEPROP 0 LAST CDS_SEC 1
J 0
(-5175 4450);
DISPLAY 0.680851 (-5175 4450);
DISPLAY INVISIBLE (-5175 4450);
FORCEPROP 0 LASTPIN (-5000 4350) $PN 1
J 2
(-5010 4360);
DISPLAY 0.680851 (-5010 4360);
PAINT MONO (-5010 4360);
FORCEPROP 0 LASTPIN (-4800 4350) $PN 2
J 0
(-4790 4360);
DISPLAY 0.680851 (-4790 4360);
PAINT MONO (-4790 4360);
FORCEPROP 2 LAST VALUE 120NH/69A
J 0
(-4725 4375);
DISPLAY 0.617021 (-4725 4375);
FORCEPROP 2 LAST PACK_TYPE SMLF
J 0
(-4575 4300);
DISPLAY 0.617021 (-4575 4300);
FORCEPROP 1 LAST MATERIAL IND
J 0
(-5200 4350);
DISPLAY 0.723404 (-5200 4350);
PAINT GREEN (-5200 4350);
FORCEPROP 1 LAST PATH I65
J 0
(-4825 4430);
DISPLAY 0.723404 (-4825 4430);
PAINT GREEN (-4825 4430);
DISPLAY INVISIBLE (-4825 4430);
FORCEPROP 1 LAST PART_NUMBER CV+12^0EZ03
J 0
(-5200 4300);
DISPLAY 0.723404 (-5200 4300);
PAINT GREEN (-5200 4300);
DISPLAY INVISIBLE (-5200 4300);
FORCEPROP 2 LAST CDS_LIB pure_quanta
J 0
(-4900 4375);
DISPLAY INVISIBLE (-4900 4375);
FORCEPROP 1 LAST NEEDS_NO_SIZE TRUE
J 0
(-4900 4375);
DISPLAY 0.468085 (-4900 4375);
PAINT GREEN (-4900 4375);
DISPLAY INVISIBLE (-4900 4375);
FORCEPROP 2 LAST BOM_COST VR_DIMM 
J 0
(-4725 4425);
DISPLAY 0.680851 (-4725 4425);
DISPLAY INVISIBLE (-4725 4425);
FORCEADD Q_CAP..1
(-4125 4200);
FORCEPROP 1 LAST LOCATION PC6623
J 0
(-4075 4300);
DISPLAY 0.978723 (-4075 4300);
FORCEPROP 0 LAST $SEC 1
J 0
(-4075 4350);
DISPLAY 0.680851 (-4075 4350);
PAINT MONO (-4075 4350);
DISPLAY INVISIBLE (-4075 4350);
FORCEPROP 0 LAST CDS_SEC 1
J 0
(-4075 4350);
DISPLAY 0.680851 (-4075 4350);
DISPLAY INVISIBLE (-4075 4350);
FORCEPROP 1 LASTPIN (-4125 4300) $PN 1
J 0
(-4115 4280);
DISPLAY 0.787234 (-4115 4280);
PAINT MONO (-4115 4280);
FORCEPROP 1 LASTPIN (-4125 4100) $PN 2
J 0
(-4115 4080);
DISPLAY 0.787234 (-4115 4080);
PAINT MONO (-4115 4080);
FORCEPROP 1 LAST VALUE 100NF
J 0
(-4075 4250);
DISPLAY 0.489362 (-4075 4250);
FORCEPROP 1 LAST PACK_TYPE C0402
J 0
(-4075 4000);
DISPLAY 0.489362 (-4075 4000);
FORCEPROP 1 LAST MATERIAL X7R
J 0
(-4075 4100);
DISPLAY 0.489362 (-4075 4100);
FORCEPROP 1 LAST VOLTAGE 50V
J 0
(-4075 4200);
DISPLAY 0.489362 (-4075 4200);
FORCEPROP 1 LAST TOLERANCE 10%
J 0
(-4075 4150);
DISPLAY 0.489362 (-4075 4150);
FORCEPROP 1 LAST PATH I66
J 0
(-4075 4350);
DISPLAY 0.978723 (-4075 4350);
PAINT WHITE (-4075 4350);
DISPLAY INVISIBLE (-4075 4350);
FORCEPROP 1 LAST PART_NUMBER CH4106K1B01
J 0
(-4075 4050);
DISPLAY 0.489362 (-4075 4050);
DISPLAY INVISIBLE (-4075 4050);
FORCEPROP 2 LAST CDS_LIB pure_quanta
J 0
(-4125 4200);
DISPLAY INVISIBLE (-4125 4200);
FORCEPROP 2 LAST BOM_COST VR_DIMM 
J 0
(-4075 4350);
DISPLAY 0.680851 (-4075 4350);
DISPLAY INVISIBLE (-4075 4350);
FORCEADD Q_CAP..1
(-3800 4200);
FORCEPROP 1 LAST LOCATION PC6624_1
J 0
(-3775 4300);
DISPLAY 0.638298 (-3775 4300);
FORCEPROP 0 LAST $SEC 1
J 0
(-3775 4350);
DISPLAY 0.680851 (-3775 4350);
PAINT MONO (-3775 4350);
DISPLAY INVISIBLE (-3775 4350);
FORCEPROP 0 LAST CDS_SEC 1
J 0
(-3775 4350);
DISPLAY 0.680851 (-3775 4350);
DISPLAY INVISIBLE (-3775 4350);
FORCEPROP 1 LASTPIN (-3800 4300) $PN 1
J 0
(-3790 4280);
DISPLAY 0.787234 (-3790 4280);
PAINT MONO (-3790 4280);
FORCEPROP 1 LASTPIN (-3800 4100) $PN 2
J 0
(-3790 4080);
DISPLAY 0.787234 (-3790 4080);
PAINT MONO (-3790 4080);
FORCEPROP 1 LAST PACK_TYPE C0805
J 0
(-3750 4050);
DISPLAY 0.510638 (-3750 4050);
FORCEPROP 1 LAST MATERIAL X6S
J 0
(-3750 4100);
DISPLAY 0.510638 (-3750 4100);
FORCEPROP 1 LAST VALUE 22UF
J 0
(-3750 4250);
DISPLAY 0.510638 (-3750 4250);
FORCEPROP 1 LAST VOLTAGE 4V
J 0
(-3750 4200);
DISPLAY 0.510638 (-3750 4200);
FORCEPROP 1 LAST TOLERANCE 20%
J 0
(-3750 4150);
DISPLAY 0.510638 (-3750 4150);
FORCEPROP 1 LAST PATH I67
J 0
(-3750 4350);
DISPLAY 0.978723 (-3750 4350);
PAINT WHITE (-3750 4350);
DISPLAY INVISIBLE (-3750 4350);
FORCEPROP 1 LAST PART_NUMBER CH622KMEA03
J 0
(-3750 4000);
DISPLAY 0.510638 (-3750 4000);
DISPLAY INVISIBLE (-3750 4000);
FORCEPROP 2 LAST CDS_LIB pure_quanta
J 0
(-3800 4200);
DISPLAY INVISIBLE (-3800 4200);
FORCEADD Q_CAP..1
(-3575 4200);
FORCEPROP 1 LAST LOCATION PC6625_1
J 0
(-3550 4300);
DISPLAY 0.638298 (-3550 4300);
FORCEPROP 0 LAST $SEC 1
J 0
(-3550 4350);
DISPLAY 0.680851 (-3550 4350);
PAINT MONO (-3550 4350);
DISPLAY INVISIBLE (-3550 4350);
FORCEPROP 0 LAST CDS_SEC 1
J 0
(-3550 4350);
DISPLAY 0.680851 (-3550 4350);
DISPLAY INVISIBLE (-3550 4350);
FORCEPROP 1 LASTPIN (-3575 4300) $PN 1
J 0
(-3565 4280);
DISPLAY 0.787234 (-3565 4280);
PAINT MONO (-3565 4280);
FORCEPROP 1 LASTPIN (-3575 4100) $PN 2
J 0
(-3565 4080);
DISPLAY 0.787234 (-3565 4080);
PAINT MONO (-3565 4080);
FORCEPROP 1 LAST PACK_TYPE C0805
J 0
(-3525 4050);
DISPLAY 0.510638 (-3525 4050);
FORCEPROP 1 LAST MATERIAL X6S
J 0
(-3525 4100);
DISPLAY 0.510638 (-3525 4100);
FORCEPROP 1 LAST VALUE 22UF
J 0
(-3525 4250);
DISPLAY 0.510638 (-3525 4250);
FORCEPROP 1 LAST VOLTAGE 4V
J 0
(-3525 4200);
DISPLAY 0.510638 (-3525 4200);
FORCEPROP 1 LAST TOLERANCE 20%
J 0
(-3525 4150);
DISPLAY 0.510638 (-3525 4150);
FORCEPROP 1 LAST PATH I68
J 0
(-3525 4350);
DISPLAY 0.978723 (-3525 4350);
PAINT WHITE (-3525 4350);
DISPLAY INVISIBLE (-3525 4350);
FORCEPROP 1 LAST PART_NUMBER CH622KMEA03
J 0
(-3525 4050);
DISPLAY 0.510638 (-3525 4050);
DISPLAY INVISIBLE (-3525 4050);
FORCEPROP 2 LAST CDS_LIB pure_quanta
J 0
(-3575 4200);
DISPLAY INVISIBLE (-3575 4200);
FORCEADD Q_CAPP..1
(-3350 4200);
FORCEPROP 1 LAST LOCATION PC6626
J 0
(-3300 4300);
DISPLAY 0.638298 (-3300 4300);
FORCEPROP 0 LAST $SEC 1
J 0
(-3300 4350);
DISPLAY 0.680851 (-3300 4350);
PAINT MONO (-3300 4350);
DISPLAY INVISIBLE (-3300 4350);
FORCEPROP 0 LAST CDS_SEC 1
J 0
(-3300 4350);
DISPLAY 0.680851 (-3300 4350);
DISPLAY INVISIBLE (-3300 4350);
FORCEPROP 1 LASTPIN (-3350 4300) $PN 1
J 0
(-3340 4285);
DISPLAY 0.787234 (-3340 4285);
PAINT MONO (-3340 4285);
FORCEPROP 1 LASTPIN (-3350 4100) $PN 2
J 0
(-3340 4085);
DISPLAY 0.787234 (-3340 4085);
PAINT MONO (-3340 4085);
FORCEPROP 1 LAST MATERIAL SPCAP
J 0
(-3300 4100);
DISPLAY 0.510638 (-3300 4100);
FORCEPROP 1 LAST VOLTAGE 2.5V
J 0
(-3300 4150);
DISPLAY 0.510638 (-3300 4150);
FORCEPROP 1 LAST VALUE 470UF
J 0
(-3300 4250);
DISPLAY 0.510638 (-3300 4250);
FORCEPROP 1 LAST TOLERANCE 20%
J 0
(-3300 4200);
DISPLAY 0.510638 (-3300 4200);
FORCEPROP 1 LAST PACK_TYPE SMLF
J 0
(-3300 4050);
DISPLAY 0.510638 (-3300 4050);
FORCEPROP 1 LAST PATH I69
J 0
(-3300 4350);
DISPLAY 0.978723 (-3300 4350);
DISPLAY INVISIBLE (-3300 4350);
FORCEPROP 1 LAST PART_NUMBER CH747LM8818
J 0
(-3300 4000);
DISPLAY 0.510638 (-3300 4000);
DISPLAY INVISIBLE (-3300 4000);
FORCEPROP 2 LAST CDS_LIB pure_quanta
J 0
(-3350 4200);
DISPLAY INVISIBLE (-3350 4200);
FORCEADD OFFPAGE..4
R 2
(-8225 850);
FORCEPROP 2 LAST $XR0 365 
J 0
(-8477 850);
DISPLAY 0.638298 (-8477 850);
PAINT MONO (-8477 850);
FORCEPROP 2 LAST PATH I7
J 0
(-8175 925);
DISPLAY 0.680851 (-8175 925);
DISPLAY INVISIBLE (-8175 925);
FORCEPROP 1 LAST COMMENT_BODY TRUE
J 2
(-8200 750);
DISPLAY 0.872340 (-8200 750);
PAINT GREEN (-8200 750);
DISPLAY INVISIBLE (-8200 750);
FORCEPROP 1 LAST OFFPAGE TRUE
J 2
(-8550 725);
DISPLAY 0.872340 (-8550 725);
PAINT GREEN (-8550 725);
DISPLAY INVISIBLE (-8550 725);
FORCEPROP 2 LAST CDS_LIB standard
J 0
(-8225 850);
DISPLAY INVISIBLE (-8225 850);
FORCEPROP 2 LAST BOM_COST VR_DIMM 
J 0
(-8520 900);
DISPLAY 0.680851 (-8520 900);
DISPLAY INVISIBLE (-8520 900);
FORCEADD Q_CAPP..1
(-3125 4200);
FORCEPROP 1 LAST LOCATION PC6627
J 0
(-3075 4300);
DISPLAY 0.638298 (-3075 4300);
FORCEPROP 0 LAST $SEC 1
J 0
(-3075 4350);
DISPLAY 0.680851 (-3075 4350);
PAINT MONO (-3075 4350);
DISPLAY INVISIBLE (-3075 4350);
FORCEPROP 0 LAST CDS_SEC 1
J 0
(-3075 4350);
DISPLAY 0.680851 (-3075 4350);
DISPLAY INVISIBLE (-3075 4350);
FORCEPROP 1 LASTPIN (-3125 4300) $PN 1
J 0
(-3115 4285);
DISPLAY 0.787234 (-3115 4285);
PAINT MONO (-3115 4285);
FORCEPROP 1 LASTPIN (-3125 4100) $PN 2
J 0
(-3115 4085);
DISPLAY 0.787234 (-3115 4085);
PAINT MONO (-3115 4085);
FORCEPROP 1 LAST MATERIAL SPCAP
J 0
(-3075 4100);
DISPLAY 0.510638 (-3075 4100);
FORCEPROP 1 LAST VOLTAGE 2.5V
J 0
(-3075 4150);
DISPLAY 0.510638 (-3075 4150);
FORCEPROP 1 LAST VALUE 470UF
J 0
(-3075 4250);
DISPLAY 0.510638 (-3075 4250);
FORCEPROP 1 LAST PACK_TYPE SMLF
J 0
(-3075 4050);
DISPLAY 0.510638 (-3075 4050);
FORCEPROP 1 LAST TOLERANCE 20%
J 0
(-3075 4200);
DISPLAY 0.510638 (-3075 4200);
FORCEPROP 1 LAST PATH I70
J 0
(-3075 4350);
DISPLAY 0.978723 (-3075 4350);
DISPLAY INVISIBLE (-3075 4350);
FORCEPROP 1 LAST PART_NUMBER CH747LM8818
J 0
(-3075 4000);
DISPLAY 0.510638 (-3075 4000);
DISPLAY INVISIBLE (-3075 4000);
FORCEPROP 2 LAST CDS_LIB pure_quanta
J 0
(-3125 4200);
DISPLAY INVISIBLE (-3125 4200);
FORCEADD UNIVERSAL_GND..1
(-4975 4875);
FORCEPROP 3 LASTPIN (-4975 4925) SIG_NAME GND\g
J 0
(-4965 4935);
DISPLAY 0.659574 (-4965 4935);
PAINT MONO (-4965 4935);
DISPLAY INVISIBLE (-4965 4935);
FORCEPROP 1 LAST PATH I71
J 0
(-4900 4875);
DISPLAY 0.872340 (-4900 4875);
PAINT AQUA (-4900 4875);
DISPLAY INVISIBLE (-4900 4875);
FORCEPROP 1 LAST HDL_POWER GND
J 1
(-4950 4800);
DISPLAY 0.872340 (-4950 4800);
PAINT GREEN (-4950 4800);
DISPLAY INVISIBLE (-4950 4800);
FORCEPROP 2 LAST CDS_LIB pure_quanta_power
J 0
(-4975 4875);
DISPLAY INVISIBLE (-4975 4875);
FORCEADD Q_CAP..1
(-4975 5150);
FORCEPROP 1 LAST LOCATION PC6614_1
J 0
(-4925 5250);
DISPLAY 0.978723 (-4925 5250);
FORCEPROP 0 LAST $SEC 1
J 0
(-4925 5300);
DISPLAY 0.680851 (-4925 5300);
PAINT MONO (-4925 5300);
DISPLAY INVISIBLE (-4925 5300);
FORCEPROP 0 LAST CDS_SEC 1
J 0
(-4925 5300);
DISPLAY 0.680851 (-4925 5300);
DISPLAY INVISIBLE (-4925 5300);
FORCEPROP 1 LASTPIN (-4975 5250) $PN 1
J 0
(-4965 5230);
DISPLAY 0.787234 (-4965 5230);
PAINT MONO (-4965 5230);
FORCEPROP 1 LASTPIN (-4975 5050) $PN 2
J 0
(-4965 5030);
DISPLAY 0.787234 (-4965 5030);
PAINT MONO (-4965 5030);
FORCEPROP 1 LAST PACK_TYPE C0805
J 0
(-4925 4950);
DISPLAY 0.638298 (-4925 4950);
FORCEPROP 1 LAST VOLTAGE 16V
J 0
(-4925 5150);
DISPLAY 0.638298 (-4925 5150);
FORCEPROP 1 LAST TOLERANCE 20%
J 0
(-4925 5100);
DISPLAY 0.638298 (-4925 5100);
FORCEPROP 1 LAST VALUE 22UF
J 0
(-4925 5200);
DISPLAY 0.638298 (-4925 5200);
FORCEPROP 1 LAST MATERIAL X6S
J 0
(-4925 5050);
DISPLAY 0.638298 (-4925 5050);
FORCEPROP 1 LAST PATH I72
J 0
(-4925 5300);
DISPLAY 0.978723 (-4925 5300);
PAINT WHITE (-4925 5300);
DISPLAY INVISIBLE (-4925 5300);
FORCEPROP 1 LAST PART_NUMBER CH6223MEA01
J 0
(-4925 5000);
DISPLAY 0.638298 (-4925 5000);
DISPLAY INVISIBLE (-4925 5000);
FORCEPROP 2 LAST CDS_LIB pure_quanta
J 0
(-4975 5150);
DISPLAY INVISIBLE (-4975 5150);
FORCEPROP 0 LAST REUSE_ID 41
J 0
(-4925 5350);
DISPLAY 0.680851 (-4925 5350);
DISPLAY INVISIBLE (-4925 5350);
FORCEPROP 2 LAST BOM_COST VR_DIMM 
J 0
(-4925 5300);
DISPLAY 0.680851 (-4925 5300);
DISPLAY INVISIBLE (-4925 5300);
FORCEADD UNIVERSAL_GND..1
(-4475 4875);
FORCEPROP 3 LASTPIN (-4475 4925) SIG_NAME GND\g
J 0
(-4465 4935);
DISPLAY 0.659574 (-4465 4935);
PAINT MONO (-4465 4935);
DISPLAY INVISIBLE (-4465 4935);
FORCEPROP 1 LAST PATH I73
J 0
(-4400 4875);
DISPLAY 0.872340 (-4400 4875);
PAINT AQUA (-4400 4875);
DISPLAY INVISIBLE (-4400 4875);
FORCEPROP 1 LAST HDL_POWER GND
J 1
(-4450 4800);
DISPLAY 0.872340 (-4450 4800);
PAINT GREEN (-4450 4800);
DISPLAY INVISIBLE (-4450 4800);
FORCEPROP 2 LAST CDS_LIB pure_quanta_power
J 0
(-4475 4875);
DISPLAY INVISIBLE (-4475 4875);
FORCEADD Q_CAP..1
(-4475 5150);
FORCEPROP 1 LAST LOCATION PC6615_1
J 0
(-4425 5250);
DISPLAY 0.978723 (-4425 5250);
FORCEPROP 0 LAST $SEC 1
J 0
(-4425 5300);
DISPLAY 0.680851 (-4425 5300);
PAINT MONO (-4425 5300);
DISPLAY INVISIBLE (-4425 5300);
FORCEPROP 0 LAST CDS_SEC 1
J 0
(-4425 5300);
DISPLAY 0.680851 (-4425 5300);
DISPLAY INVISIBLE (-4425 5300);
FORCEPROP 1 LASTPIN (-4475 5250) $PN 1
J 0
(-4465 5230);
DISPLAY 0.787234 (-4465 5230);
PAINT MONO (-4465 5230);
FORCEPROP 1 LASTPIN (-4475 5050) $PN 2
J 0
(-4465 5030);
DISPLAY 0.787234 (-4465 5030);
PAINT MONO (-4465 5030);
FORCEPROP 1 LAST PACK_TYPE C0805
J 0
(-4425 4950);
DISPLAY 0.638298 (-4425 4950);
FORCEPROP 1 LAST TOLERANCE 20%
J 0
(-4425 5100);
DISPLAY 0.638298 (-4425 5100);
FORCEPROP 1 LAST VOLTAGE 16V
J 0
(-4425 5150);
DISPLAY 0.638298 (-4425 5150);
FORCEPROP 1 LAST VALUE 22UF
J 0
(-4425 5200);
DISPLAY 0.638298 (-4425 5200);
FORCEPROP 1 LAST MATERIAL X6S
J 0
(-4425 5050);
DISPLAY 0.638298 (-4425 5050);
FORCEPROP 1 LAST PATH I74
J 0
(-4425 5300);
DISPLAY 0.978723 (-4425 5300);
PAINT WHITE (-4425 5300);
DISPLAY INVISIBLE (-4425 5300);
FORCEPROP 1 LAST PART_NUMBER CH6223MEA01
J 0
(-4425 5000);
DISPLAY 0.638298 (-4425 5000);
DISPLAY INVISIBLE (-4425 5000);
FORCEPROP 2 LAST CDS_LIB pure_quanta
J 0
(-4475 5150);
DISPLAY INVISIBLE (-4475 5150);
FORCEPROP 0 LAST REUSE_ID 41
J 0
(-4425 5350);
DISPLAY 0.680851 (-4425 5350);
DISPLAY INVISIBLE (-4425 5350);
FORCEPROP 2 LAST BOM_COST VR_DIMM 
J 0
(-4425 5300);
DISPLAY 0.680851 (-4425 5300);
DISPLAY INVISIBLE (-4425 5300);
FORCEADD UNIVERSAL_GND..1
(-4000 4875);
FORCEPROP 3 LASTPIN (-4000 4925) SIG_NAME GND\g
J 0
(-3990 4935);
DISPLAY 0.659574 (-3990 4935);
PAINT MONO (-3990 4935);
DISPLAY INVISIBLE (-3990 4935);
FORCEPROP 1 LAST PATH I75
J 0
(-3925 4875);
DISPLAY 0.872340 (-3925 4875);
PAINT AQUA (-3925 4875);
DISPLAY INVISIBLE (-3925 4875);
FORCEPROP 1 LAST HDL_POWER GND
J 1
(-3975 4800);
DISPLAY 0.872340 (-3975 4800);
PAINT GREEN (-3975 4800);
DISPLAY INVISIBLE (-3975 4800);
FORCEPROP 2 LAST CDS_LIB pure_quanta_power
J 0
(-4000 4875);
DISPLAY INVISIBLE (-4000 4875);
FORCEADD Q_CAP..2
(-4100 4700);
FORCEPROP 1 LAST LOCATION PC6621
J 1
(-4100 4800);
DISPLAY 0.978723 (-4100 4800);
FORCEPROP 0 LAST $SEC 1
J 0
(-4100 4850);
DISPLAY 0.680851 (-4100 4850);
PAINT MONO (-4100 4850);
DISPLAY INVISIBLE (-4100 4850);
FORCEPROP 0 LAST CDS_SEC 1
J 0
(-4100 4850);
DISPLAY 0.680851 (-4100 4850);
DISPLAY INVISIBLE (-4100 4850);
FORCEPROP 1 LASTPIN (-4200 4700) $PN 1
J 0
(-4210 4715);
DISPLAY 0.787234 (-4210 4715);
PAINT MONO (-4210 4715);
FORCEPROP 1 LASTPIN (-4000 4700) $PN 2
J 0
(-4015 4715);
DISPLAY 0.787234 (-4015 4715);
PAINT MONO (-4015 4715);
FORCEPROP 1 LAST PACK_TYPE C0402
J 1
(-4100 4500);
DISPLAY 0.617021 (-4100 4500);
FORCEPROP 1 LAST TOLERANCE 10%
J 2
(-4100 4550);
DISPLAY 0.617021 (-4100 4550);
FORCEPROP 1 LAST MATERIAL X7R
J 0
(-4100 4550);
DISPLAY 0.617021 (-4100 4550);
FORCEPROP 1 LAST VOLTAGE 50V
J 0
(-4100 4600);
DISPLAY 0.617021 (-4100 4600);
FORCEPROP 1 LAST VALUE 100NF
J 2
(-4100 4600);
DISPLAY 0.617021 (-4100 4600);
FORCEPROP 1 LAST PATH I76
J 0
(-4100 4900);
DISPLAY 0.978723 (-4100 4900);
PAINT WHITE (-4100 4900);
DISPLAY INVISIBLE (-4100 4900);
FORCEPROP 1 LAST PART_NUMBER CH4106K1B01
J 1
(-4100 4750);
DISPLAY 0.617021 (-4100 4750);
DISPLAY INVISIBLE (-4100 4750);
FORCEPROP 2 LAST CDS_LIB pure_quanta
J 0
(-4100 4700);
DISPLAY INVISIBLE (-4100 4700);
FORCEPROP 2 LAST BOM_COST VR_DIMM 
J 0
(-4100 4850);
DISPLAY 0.680851 (-4100 4850);
DISPLAY INVISIBLE (-4100 4850);
FORCEPROP 0 LAST REUSE_ID 55
J 0
(-4125 4800);
DISPLAY 0.680851 (-4125 4800);
DISPLAY INVISIBLE (-4125 4800);
FORCEADD Q_CAP..1
(-4000 5150);
FORCEPROP 1 LAST LOCATION PC6616_1
J 0
(-3950 5250);
DISPLAY 0.978723 (-3950 5250);
FORCEPROP 0 LAST $SEC 1
J 0
(-3950 5300);
DISPLAY 0.680851 (-3950 5300);
PAINT MONO (-3950 5300);
DISPLAY INVISIBLE (-3950 5300);
FORCEPROP 0 LAST CDS_SEC 1
J 0
(-3950 5300);
DISPLAY 0.680851 (-3950 5300);
DISPLAY INVISIBLE (-3950 5300);
FORCEPROP 1 LASTPIN (-4000 5250) $PN 1
J 0
(-3990 5230);
DISPLAY 0.787234 (-3990 5230);
PAINT MONO (-3990 5230);
FORCEPROP 1 LASTPIN (-4000 5050) $PN 2
J 0
(-3990 5030);
DISPLAY 0.787234 (-3990 5030);
PAINT MONO (-3990 5030);
FORCEPROP 1 LAST VOLTAGE 16V
J 0
(-3950 5150);
DISPLAY 0.638298 (-3950 5150);
FORCEPROP 1 LAST MATERIAL X6S
J 0
(-3950 5050);
DISPLAY 0.638298 (-3950 5050);
FORCEPROP 1 LAST TOLERANCE 20%
J 0
(-3950 5100);
DISPLAY 0.638298 (-3950 5100);
FORCEPROP 1 LAST PACK_TYPE C0805
J 0
(-3950 4950);
DISPLAY 0.638298 (-3950 4950);
FORCEPROP 1 LAST VALUE 22UF
J 0
(-3950 5200);
DISPLAY 0.638298 (-3950 5200);
FORCEPROP 1 LAST PATH I77
J 0
(-3950 5300);
DISPLAY 0.978723 (-3950 5300);
PAINT WHITE (-3950 5300);
DISPLAY INVISIBLE (-3950 5300);
FORCEPROP 1 LAST PART_NUMBER CH6223MEA01
J 0
(-3950 5000);
DISPLAY 0.638298 (-3950 5000);
DISPLAY INVISIBLE (-3950 5000);
FORCEPROP 2 LAST CDS_LIB pure_quanta
J 0
(-4000 5150);
DISPLAY INVISIBLE (-4000 5150);
FORCEPROP 2 LAST BOM_COST VR_DIMM 
J 0
(-3950 5300);
DISPLAY 0.680851 (-3950 5300);
DISPLAY INVISIBLE (-3950 5300);
FORCEPROP 0 LAST REUSE_ID 41
J 0
(-3950 5350);
DISPLAY 0.680851 (-3950 5350);
DISPLAY INVISIBLE (-3950 5350);
FORCEADD UNIVERSAL_GND..1
(-3625 4875);
FORCEPROP 3 LASTPIN (-3625 4925) SIG_NAME GND\g
J 0
(-3615 4935);
DISPLAY 0.659574 (-3615 4935);
PAINT MONO (-3615 4935);
DISPLAY INVISIBLE (-3615 4935);
FORCEPROP 1 LAST PATH I78
J 0
(-3550 4875);
DISPLAY 0.872340 (-3550 4875);
PAINT AQUA (-3550 4875);
DISPLAY INVISIBLE (-3550 4875);
FORCEPROP 1 LAST HDL_POWER GND
J 1
(-3600 4800);
DISPLAY 0.872340 (-3600 4800);
PAINT GREEN (-3600 4800);
DISPLAY INVISIBLE (-3600 4800);
FORCEPROP 2 LAST CDS_LIB pure_quanta_power
J 0
(-3625 4875);
DISPLAY INVISIBLE (-3625 4875);
FORCEADD Q_CAP..1
(-3625 5150);
FORCEPROP 1 LAST LOCATION PC6617_1
J 0
(-3575 5250);
DISPLAY 0.978723 (-3575 5250);
FORCEPROP 0 LAST $SEC 1
J 0
(-3575 5300);
DISPLAY 0.680851 (-3575 5300);
PAINT MONO (-3575 5300);
DISPLAY INVISIBLE (-3575 5300);
FORCEPROP 0 LAST CDS_SEC 1
J 0
(-3575 5300);
DISPLAY 0.680851 (-3575 5300);
DISPLAY INVISIBLE (-3575 5300);
FORCEPROP 1 LASTPIN (-3625 5250) $PN 1
J 0
(-3615 5230);
DISPLAY 0.787234 (-3615 5230);
PAINT MONO (-3615 5230);
FORCEPROP 1 LASTPIN (-3625 5050) $PN 2
J 0
(-3615 5030);
DISPLAY 0.787234 (-3615 5030);
PAINT MONO (-3615 5030);
FORCEPROP 1 LAST MATERIAL X6S
J 0
(-3575 5050);
DISPLAY 0.638298 (-3575 5050);
FORCEPROP 1 LAST PACK_TYPE C0805
J 0
(-3575 4950);
DISPLAY 0.638298 (-3575 4950);
FORCEPROP 1 LAST VALUE 22UF
J 0
(-3575 5200);
DISPLAY 0.638298 (-3575 5200);
FORCEPROP 1 LAST VOLTAGE 16V
J 0
(-3575 5150);
DISPLAY 0.638298 (-3575 5150);
FORCEPROP 1 LAST TOLERANCE 20%
J 0
(-3575 5100);
DISPLAY 0.638298 (-3575 5100);
FORCEPROP 1 LAST PATH I79
J 0
(-3575 5300);
DISPLAY 0.978723 (-3575 5300);
PAINT WHITE (-3575 5300);
DISPLAY INVISIBLE (-3575 5300);
FORCEPROP 1 LAST PART_NUMBER CH6223MEA01
J 0
(-3575 5000);
DISPLAY 0.638298 (-3575 5000);
DISPLAY INVISIBLE (-3575 5000);
FORCEPROP 2 LAST CDS_LIB pure_quanta
J 0
(-3625 5150);
DISPLAY INVISIBLE (-3625 5150);
FORCEPROP 0 LAST REUSE_ID 41
J 0
(-3575 5350);
DISPLAY 0.680851 (-3575 5350);
DISPLAY INVISIBLE (-3575 5350);
FORCEPROP 2 LAST BOM_COST VR_DIMM 
J 0
(-3575 5300);
DISPLAY 0.680851 (-3575 5300);
DISPLAY INVISIBLE (-3575 5300);
FORCEADD OFFPAGE..2
R 2
(-8250 950);
FORCEPROP 2 LAST $XR1 365 
J 0
(-8505 914);
DISPLAY 0.638298 (-8505 914);
PAINT MONO (-8505 914);
FORCEPROP 2 LAST $XR0 366 
J 0
(-8505 950);
DISPLAY 0.638298 (-8505 950);
PAINT MONO (-8505 950);
FORCEPROP 2 LAST PATH I8
J 0
(-8200 1025);
DISPLAY 0.680851 (-8200 1025);
DISPLAY INVISIBLE (-8200 1025);
FORCEPROP 1 LAST COMMENT_BODY TRUE
J 2
(-8205 855);
DISPLAY 1.170213 (-8205 855);
PAINT GREEN (-8205 855);
DISPLAY INVISIBLE (-8205 855);
FORCEPROP 1 LAST OFFPAGE TRUE
J 2
(-8575 825);
DISPLAY 1.170213 (-8575 825);
PAINT GREEN (-8575 825);
DISPLAY INVISIBLE (-8575 825);
FORCEPROP 2 LAST CDS_LIB standard
J 0
(-8250 950);
DISPLAY INVISIBLE (-8250 950);
FORCEPROP 2 LAST BOM_COST VR_DIMM 
J 0
(-8531 1000);
DISPLAY 0.680851 (-8531 1000);
DISPLAY INVISIBLE (-8531 1000);
FORCEADD Q_CAP..1
(-3225 5100);
FORCEPROP 1 LAST LOCATION PC6618
J 0
(-3175 5200);
DISPLAY 0.978723 (-3175 5200);
FORCEPROP 0 LAST $SEC 1
J 0
(-3175 5250);
DISPLAY 0.680851 (-3175 5250);
PAINT MONO (-3175 5250);
DISPLAY INVISIBLE (-3175 5250);
FORCEPROP 0 LAST CDS_SEC 1
J 0
(-3175 5250);
DISPLAY 0.680851 (-3175 5250);
DISPLAY INVISIBLE (-3175 5250);
FORCEPROP 1 LASTPIN (-3225 5200) $PN 1
J 0
(-3215 5180);
DISPLAY 0.787234 (-3215 5180);
PAINT MONO (-3215 5180);
FORCEPROP 1 LASTPIN (-3225 5000) $PN 2
J 0
(-3215 4980);
DISPLAY 0.787234 (-3215 4980);
PAINT MONO (-3215 4980);
FORCEPROP 1 LAST PACK_TYPE C0805
J 0
(-3175 4900);
DISPLAY 0.510638 (-3175 4900);
FORCEPROP 1 LAST TOLERANCE 20%
J 0
(-3175 5050);
DISPLAY 0.510638 (-3175 5050);
FORCEPROP 1 LAST MATERIAL X6S
J 0
(-3175 5000);
DISPLAY 0.510638 (-3175 5000);
FORCEPROP 1 LAST VALUE 22UF
J 0
(-3175 5150);
DISPLAY 0.510638 (-3175 5150);
FORCEPROP 1 LAST VOLTAGE 16V
J 0
(-3175 5100);
DISPLAY 0.510638 (-3175 5100);
FORCEPROP 1 LAST PATH I80
J 0
(-3175 5250);
DISPLAY 0.978723 (-3175 5250);
PAINT WHITE (-3175 5250);
DISPLAY INVISIBLE (-3175 5250);
FORCEPROP 1 LAST PART_NUMBER CH6223MEA01
J 0
(-3175 4950);
DISPLAY 0.510638 (-3175 4950);
DISPLAY INVISIBLE (-3175 4950);
FORCEPROP 2 LAST CDS_LIB pure_quanta
J 0
(-3225 5100);
DISPLAY INVISIBLE (-3225 5100);
FORCEADD UNIVERSAL_GND..1
(-3225 4875);
FORCEPROP 3 LASTPIN (-3225 4925) SIG_NAME GND\g
J 0
(-3215 4935);
DISPLAY 0.659574 (-3215 4935);
PAINT MONO (-3215 4935);
DISPLAY INVISIBLE (-3215 4935);
FORCEPROP 1 LAST PATH I81
J 0
(-3150 4875);
DISPLAY 0.872340 (-3150 4875);
PAINT AQUA (-3150 4875);
DISPLAY INVISIBLE (-3150 4875);
FORCEPROP 1 LAST HDL_POWER GND
J 1
(-3200 4800);
DISPLAY 0.872340 (-3200 4800);
PAINT GREEN (-3200 4800);
DISPLAY INVISIBLE (-3200 4800);
FORCEPROP 2 LAST CDS_LIB pure_quanta_power
J 0
(-3225 4875);
DISPLAY INVISIBLE (-3225 4875);
FORCEADD Q_CAPP..1
(-2800 1300);
FORCEPROP 1 LAST LOCATION PC6815
J 0
(-2750 1400);
DISPLAY 0.638298 (-2750 1400);
FORCEPROP 0 LAST $SEC 1
J 0
(-2750 1450);
DISPLAY 0.680851 (-2750 1450);
PAINT MONO (-2750 1450);
DISPLAY INVISIBLE (-2750 1450);
FORCEPROP 0 LAST CDS_SEC 1
J 0
(-2750 1450);
DISPLAY 0.680851 (-2750 1450);
DISPLAY INVISIBLE (-2750 1450);
FORCEPROP 1 LASTPIN (-2800 1400) $PN 1
J 0
(-2790 1385);
DISPLAY 0.787234 (-2790 1385);
PAINT MONO (-2790 1385);
FORCEPROP 1 LASTPIN (-2800 1200) $PN 2
J 0
(-2790 1185);
DISPLAY 0.787234 (-2790 1185);
PAINT MONO (-2790 1185);
FORCEPROP 1 LAST MATERIAL SPCAP
J 0
(-2750 1200);
DISPLAY 0.510638 (-2750 1200);
FORCEPROP 1 LAST VOLTAGE 2.5V
J 0
(-2750 1250);
DISPLAY 0.510638 (-2750 1250);
FORCEPROP 1 LAST VALUE 470UF
J 0
(-2750 1350);
DISPLAY 0.510638 (-2750 1350);
FORCEPROP 1 LAST PACK_TYPE SMLF
J 0
(-2750 1150);
DISPLAY 0.510638 (-2750 1150);
FORCEPROP 1 LAST TOLERANCE 20%
J 0
(-2750 1300);
DISPLAY 0.510638 (-2750 1300);
FORCEPROP 1 LAST PATH I82
J 0
(-2750 1450);
DISPLAY 0.978723 (-2750 1450);
DISPLAY INVISIBLE (-2750 1450);
FORCEPROP 1 LAST PART_NUMBER CH747LM8818
J 0
(-2750 1100);
DISPLAY 0.510638 (-2750 1100);
DISPLAY INVISIBLE (-2750 1100);
FORCEPROP 2 LAST CDS_LIB pure_quanta
J 0
(-2800 1300);
DISPLAY INVISIBLE (-2800 1300);
FORCEADD Q_CAPP..1
(-2475 1300);
FORCEPROP 1 LAST LOCATION PC6631
J 0
(-2425 1400);
DISPLAY 0.638298 (-2425 1400);
FORCEPROP 0 LAST $SEC 1
J 0
(-2425 1450);
DISPLAY 0.680851 (-2425 1450);
PAINT MONO (-2425 1450);
DISPLAY INVISIBLE (-2425 1450);
FORCEPROP 0 LAST CDS_SEC 1
J 0
(-2425 1450);
DISPLAY 0.680851 (-2425 1450);
DISPLAY INVISIBLE (-2425 1450);
FORCEPROP 1 LASTPIN (-2475 1400) $PN 1
J 0
(-2465 1385);
DISPLAY 0.787234 (-2465 1385);
PAINT MONO (-2465 1385);
FORCEPROP 1 LASTPIN (-2475 1200) $PN 2
J 0
(-2465 1185);
DISPLAY 0.787234 (-2465 1185);
PAINT MONO (-2465 1185);
FORCEPROP 1 LAST TOLERANCE 20%
J 0
(-2425 1300);
DISPLAY 0.510638 (-2425 1300);
FORCEPROP 1 LAST VALUE 390UF
J 0
(-2425 1350);
DISPLAY 0.510638 (-2425 1350);
FORCEPROP 1 LAST VOLTAGE 2.5V
J 0
(-2425 1250);
DISPLAY 0.510638 (-2425 1250);
FORCEPROP 1 LAST PACK_TYPE SMLF
J 0
(-2425 1150);
DISPLAY 0.510638 (-2425 1150);
FORCEPROP 1 LAST MATERIAL ALUM
J 0
(-2425 1200);
DISPLAY 0.510638 (-2425 1200);
FORCEPROP 1 LAST PATH I83
J 0
(-2425 1450);
DISPLAY 0.978723 (-2425 1450);
DISPLAY INVISIBLE (-2425 1450);
FORCEPROP 1 LAST PART_NUMBER CC7390JMZ13
J 0
(-2425 1100);
DISPLAY 0.510638 (-2425 1100);
DISPLAY INVISIBLE (-2425 1100);
FORCEPROP 2 LAST CDS_LIB pure_quanta
J 0
(-2475 1300);
DISPLAY INVISIBLE (-2475 1300);
FORCEADD Q_CAPP..1
(-2225 1300);
FORCEPROP 1 LAST LOCATION PC6632
J 0
(-2175 1400);
DISPLAY 0.638298 (-2175 1400);
FORCEPROP 0 LAST $SEC 1
J 0
(-2175 1450);
DISPLAY 0.680851 (-2175 1450);
PAINT MONO (-2175 1450);
DISPLAY INVISIBLE (-2175 1450);
FORCEPROP 0 LAST CDS_SEC 1
J 0
(-2175 1450);
DISPLAY 0.680851 (-2175 1450);
DISPLAY INVISIBLE (-2175 1450);
FORCEPROP 1 LASTPIN (-2225 1400) $PN 1
J 0
(-2215 1385);
DISPLAY 0.787234 (-2215 1385);
PAINT MONO (-2215 1385);
FORCEPROP 1 LASTPIN (-2225 1200) $PN 2
J 0
(-2215 1185);
DISPLAY 0.787234 (-2215 1185);
PAINT MONO (-2215 1185);
FORCEPROP 1 LAST MATERIAL ALUM
J 0
(-2175 1200);
DISPLAY 0.510638 (-2175 1200);
FORCEPROP 1 LAST PACK_TYPE SMLF
J 0
(-2175 1150);
DISPLAY 0.510638 (-2175 1150);
FORCEPROP 1 LAST VOLTAGE 2.5V
J 0
(-2175 1250);
DISPLAY 0.510638 (-2175 1250);
FORCEPROP 1 LAST TOLERANCE 20%
J 0
(-2175 1300);
DISPLAY 0.510638 (-2175 1300);
FORCEPROP 1 LAST VALUE 390UF
J 0
(-2175 1350);
DISPLAY 0.510638 (-2175 1350);
FORCEPROP 1 LAST PATH I84
J 0
(-2175 1450);
DISPLAY 0.978723 (-2175 1450);
DISPLAY INVISIBLE (-2175 1450);
FORCEPROP 1 LAST PART_NUMBER CC7390JMZ13
J 0
(-2175 1100);
DISPLAY 0.510638 (-2175 1100);
DISPLAY INVISIBLE (-2175 1100);
FORCEPROP 2 LAST CDS_LIB pure_quanta
J 0
(-2225 1300);
DISPLAY INVISIBLE (-2225 1300);
FORCEADD UNIVERSAL_GND..1
(-2650 1975);
FORCEPROP 3 LASTPIN (-2650 2025) SIG_NAME GND\g
J 0
(-2640 2035);
DISPLAY 0.659574 (-2640 2035);
PAINT MONO (-2640 2035);
DISPLAY INVISIBLE (-2640 2035);
FORCEPROP 1 LAST PATH I85
J 0
(-2575 1975);
DISPLAY 0.872340 (-2575 1975);
PAINT AQUA (-2575 1975);
DISPLAY INVISIBLE (-2575 1975);
FORCEPROP 1 LAST HDL_POWER GND
J 1
(-2625 1900);
DISPLAY 0.872340 (-2625 1900);
PAINT GREEN (-2625 1900);
DISPLAY INVISIBLE (-2625 1900);
FORCEPROP 2 LAST CDS_LIB pure_quanta_power
J 0
(-2650 1975);
DISPLAY INVISIBLE (-2650 1975);
FORCEADD Q_CAP..1
(-2650 2200);
FORCEPROP 1 LAST LOCATION PC6818
J 0
(-2600 2300);
DISPLAY 0.978723 (-2600 2300);
FORCEPROP 0 LAST $SEC 1
J 0
(-2600 2350);
DISPLAY 0.680851 (-2600 2350);
PAINT MONO (-2600 2350);
DISPLAY INVISIBLE (-2600 2350);
FORCEPROP 0 LAST CDS_SEC 1
J 0
(-2600 2350);
DISPLAY 0.680851 (-2600 2350);
DISPLAY INVISIBLE (-2600 2350);
FORCEPROP 1 LASTPIN (-2650 2300) $PN 1
J 0
(-2640 2280);
DISPLAY 0.787234 (-2640 2280);
PAINT MONO (-2640 2280);
FORCEPROP 1 LASTPIN (-2650 2100) $PN 2
J 0
(-2640 2080);
DISPLAY 0.787234 (-2640 2080);
PAINT MONO (-2640 2080);
FORCEPROP 1 LAST MATERIAL X6S
J 0
(-2600 2100);
DISPLAY 0.510638 (-2600 2100);
FORCEPROP 1 LAST PACK_TYPE C0805
J 0
(-2600 2000);
DISPLAY 0.510638 (-2600 2000);
FORCEPROP 1 LAST TOLERANCE 20%
J 0
(-2600 2150);
DISPLAY 0.510638 (-2600 2150);
FORCEPROP 1 LAST VOLTAGE 16V
J 0
(-2600 2200);
DISPLAY 0.510638 (-2600 2200);
FORCEPROP 1 LAST VALUE 22UF
J 0
(-2600 2250);
DISPLAY 0.510638 (-2600 2250);
FORCEPROP 1 LAST PATH I86
J 0
(-2600 2350);
DISPLAY 0.978723 (-2600 2350);
PAINT WHITE (-2600 2350);
DISPLAY INVISIBLE (-2600 2350);
FORCEPROP 1 LAST PART_NUMBER CH6223MEA01
J 0
(-2600 2050);
DISPLAY 0.510638 (-2600 2050);
DISPLAY INVISIBLE (-2600 2050);
FORCEPROP 2 LAST CDS_LIB pure_quanta
J 0
(-2650 2200);
DISPLAY INVISIBLE (-2650 2200);
FORCEADD UNIVERSAL_GND..1
(-2250 1950);
FORCEPROP 3 LASTPIN (-2250 2000) SIG_NAME GND\g
J 0
(-2240 2010);
DISPLAY 0.659574 (-2240 2010);
PAINT MONO (-2240 2010);
DISPLAY INVISIBLE (-2240 2010);
FORCEPROP 1 LAST PATH I87
J 0
(-2175 1950);
DISPLAY 0.872340 (-2175 1950);
PAINT AQUA (-2175 1950);
DISPLAY INVISIBLE (-2175 1950);
FORCEPROP 1 LAST HDL_POWER GND
J 1
(-2225 1875);
DISPLAY 0.872340 (-2225 1875);
PAINT GREEN (-2225 1875);
DISPLAY INVISIBLE (-2225 1875);
FORCEPROP 2 LAST CDS_LIB pure_quanta_power
J 0
(-2250 1950);
DISPLAY INVISIBLE (-2250 1950);
FORCEADD Q_CAPP..1
(-2250 2225);
FORCEPROP 1 LAST LOCATION PC473
J 0
(-2200 2325);
DISPLAY 0.787234 (-2200 2325);
FORCEPROP 0 LAST $SEC 1
J 0
(-2200 2375);
DISPLAY 0.680851 (-2200 2375);
PAINT MONO (-2200 2375);
DISPLAY INVISIBLE (-2200 2375);
FORCEPROP 0 LAST CDS_SEC 1
J 0
(-2200 2375);
DISPLAY 0.680851 (-2200 2375);
DISPLAY INVISIBLE (-2200 2375);
FORCEPROP 1 LASTPIN (-2250 2325) $PN 1
J 0
(-2240 2310);
DISPLAY 0.787234 (-2240 2310);
PAINT MONO (-2240 2310);
FORCEPROP 1 LASTPIN (-2250 2125) $PN 2
J 0
(-2240 2110);
DISPLAY 0.787234 (-2240 2110);
PAINT MONO (-2240 2110);
FORCEPROP 1 LAST PACK_TYPE SMLF
J 0
(-2200 2075);
DISPLAY 0.510638 (-2200 2075);
FORCEPROP 1 LAST MATERIAL OSCON
J 0
(-2200 2125);
DISPLAY 0.510638 (-2200 2125);
FORCEPROP 1 LAST TOLERANCE 20%
J 0
(-2200 2225);
DISPLAY 0.510638 (-2200 2225);
FORCEPROP 1 LAST VALUE 100UF
J 0
(-2200 2275);
DISPLAY 0.510638 (-2200 2275);
FORCEPROP 1 LAST VOLTAGE 16V
J 0
(-2200 2175);
DISPLAY 0.510638 (-2200 2175);
FORCEPROP 1 LAST PATH I88
J 0
(-2200 2375);
DISPLAY 0.978723 (-2200 2375);
DISPLAY INVISIBLE (-2200 2375);
FORCEPROP 1 LAST PART_NUMBER CC71003MZ30
J 0
(-2200 2025);
DISPLAY 0.510638 (-2200 2025);
DISPLAY INVISIBLE (-2200 2025);
FORCEPROP 2 LAST CDS_LIB pure_quanta
J 0
(-2250 2225);
DISPLAY INVISIBLE (-2250 2225);
FORCEADD VCC15..1
(-2300 2650);
FORCEPROP 3 LASTPIN (-2300 2600) SIG_NAME SW_P12V_AUX_P0V9_RETIMER_CPU1_FLT\g
J 0
(-2290 2610);
DISPLAY 0.659574 (-2290 2610);
PAINT MONO (-2290 2610);
DISPLAY INVISIBLE (-2290 2610);
FORCEPROP 1 LAST HDL_POWER SW_P12V_AUX_P0V9_RETIMER_CPU1_FLT
J 1
(-2400 2725);
DISPLAY 0.617021 (-2400 2725);
PAINT GREEN (-2400 2725);
FORCEPROP 1 LAST PATH I89
J 0
(-2250 2675);
DISPLAY 0.872340 (-2250 2675);
PAINT AQUA (-2250 2675);
DISPLAY INVISIBLE (-2250 2675);
FORCEPROP 2 LAST CDS_LIB pure_quanta_power
J 0
(-2300 2650);
DISPLAY INVISIBLE (-2300 2650);
FORCEPROP 2 LAST BOM_COST VR_DIMM 
J 0
(-2400 2775);
DISPLAY 0.680851 (-2400 2775);
DISPLAY INVISIBLE (-2400 2775);
FORCEADD UNIVERSAL_GND..1
(-8750 1675);
FORCEPROP 3 LASTPIN (-8750 1725) SIG_NAME GND\g
J 0
(-8740 1735);
DISPLAY 0.659574 (-8740 1735);
PAINT MONO (-8740 1735);
DISPLAY INVISIBLE (-8740 1735);
FORCEPROP 1 LAST PATH I9
J 0
(-8675 1675);
DISPLAY 0.872340 (-8675 1675);
PAINT AQUA (-8675 1675);
DISPLAY INVISIBLE (-8675 1675);
FORCEPROP 1 LAST HDL_POWER GND
J 1
(-8725 1600);
DISPLAY 0.872340 (-8725 1600);
PAINT GREEN (-8725 1600);
DISPLAY INVISIBLE (-8725 1600);
FORCEPROP 2 LAST CDS_LIB pure_quanta_power
J 0
(-8750 1675);
DISPLAY INVISIBLE (-8750 1675);
FORCEADD UNIVERSAL_GND..1
(-2225 950);
FORCEPROP 3 LASTPIN (-2225 1000) SIG_NAME GND\g
J 0
(-2215 1010);
DISPLAY 0.659574 (-2215 1010);
PAINT MONO (-2215 1010);
DISPLAY INVISIBLE (-2215 1010);
FORCEPROP 1 LAST PATH I90
J 0
(-2150 950);
DISPLAY 0.872340 (-2150 950);
PAINT AQUA (-2150 950);
DISPLAY INVISIBLE (-2150 950);
FORCEPROP 1 LAST HDL_POWER GND
J 1
(-2200 875);
DISPLAY 0.872340 (-2200 875);
PAINT GREEN (-2200 875);
DISPLAY INVISIBLE (-2200 875);
FORCEPROP 2 LAST CDS_LIB pure_quanta_power
J 0
(-2225 950);
DISPLAY INVISIBLE (-2225 950);
FORCEADD VCC15..1
(-1250 1775);
FORCEPROP 3 LASTPIN (-1250 1725) SIG_NAME P0V9_CPU1_RT_2D\g
J 0
(-1240 1735);
DISPLAY 0.659574 (-1240 1735);
PAINT MONO (-1240 1735);
DISPLAY INVISIBLE (-1240 1735);
FORCEPROP 1 LAST HDL_POWER P0V9_CPU1_RT_2D
J 1
(-1250 1825);
DISPLAY 0.617021 (-1250 1825);
PAINT GREEN (-1250 1825);
FORCEPROP 1 LAST PATH I92
J 0
(-1200 1800);
DISPLAY 0.872340 (-1200 1800);
PAINT AQUA (-1200 1800);
DISPLAY INVISIBLE (-1200 1800);
FORCEPROP 2 LAST CDS_LIB pure_quanta_power
J 0
(-1250 1775);
DISPLAY INVISIBLE (-1250 1775);
FORCEPROP 2 LAST BOM_COST VR_DIMM 
J 0
(-1250 1875);
DISPLAY 0.680851 (-1250 1875);
DISPLAY INVISIBLE (-1250 1875);
FORCEADD Q_CAPP..1
(-2925 4200);
FORCEPROP 1 LAST LOCATION PC6628
J 0
(-2875 4300);
DISPLAY 0.638298 (-2875 4300);
FORCEPROP 0 LAST $SEC 1
J 0
(-2875 4350);
DISPLAY 0.680851 (-2875 4350);
PAINT MONO (-2875 4350);
DISPLAY INVISIBLE (-2875 4350);
FORCEPROP 0 LAST CDS_SEC 1
J 0
(-2875 4350);
DISPLAY 0.680851 (-2875 4350);
DISPLAY INVISIBLE (-2875 4350);
FORCEPROP 1 LASTPIN (-2925 4300) $PN 1
J 0
(-2915 4285);
DISPLAY 0.787234 (-2915 4285);
PAINT MONO (-2915 4285);
FORCEPROP 1 LASTPIN (-2925 4100) $PN 2
J 0
(-2915 4085);
DISPLAY 0.787234 (-2915 4085);
PAINT MONO (-2915 4085);
FORCEPROP 1 LAST MATERIAL SPCAP
J 0
(-2875 4100);
DISPLAY 0.510638 (-2875 4100);
FORCEPROP 1 LAST VOLTAGE 2.5V
J 0
(-2875 4150);
DISPLAY 0.510638 (-2875 4150);
FORCEPROP 1 LAST PACK_TYPE SMLF
J 0
(-2875 4050);
DISPLAY 0.510638 (-2875 4050);
FORCEPROP 1 LAST TOLERANCE 20%
J 0
(-2875 4200);
DISPLAY 0.510638 (-2875 4200);
FORCEPROP 1 LAST VALUE 470UF
J 0
(-2875 4250);
DISPLAY 0.510638 (-2875 4250);
FORCEPROP 1 LAST PATH I93
J 0
(-2875 4350);
DISPLAY 0.978723 (-2875 4350);
DISPLAY INVISIBLE (-2875 4350);
FORCEPROP 1 LAST PART_NUMBER CH747LM8818
J 0
(-2875 4000);
DISPLAY 0.510638 (-2875 4000);
DISPLAY INVISIBLE (-2875 4000);
FORCEPROP 2 LAST CDS_LIB pure_quanta
J 0
(-2925 4200);
DISPLAY INVISIBLE (-2925 4200);
FORCEADD Q_CAPP..1
(-2600 4200);
FORCEPROP 1 LAST LOCATION PC6629
J 0
(-2550 4300);
DISPLAY 0.638298 (-2550 4300);
FORCEPROP 0 LAST $SEC 1
J 0
(-2550 4350);
DISPLAY 0.680851 (-2550 4350);
PAINT MONO (-2550 4350);
DISPLAY INVISIBLE (-2550 4350);
FORCEPROP 0 LAST CDS_SEC 1
J 0
(-2550 4350);
DISPLAY 0.680851 (-2550 4350);
DISPLAY INVISIBLE (-2550 4350);
FORCEPROP 1 LASTPIN (-2600 4300) $PN 1
J 0
(-2590 4285);
DISPLAY 0.787234 (-2590 4285);
PAINT MONO (-2590 4285);
FORCEPROP 1 LASTPIN (-2600 4100) $PN 2
J 0
(-2590 4085);
DISPLAY 0.787234 (-2590 4085);
PAINT MONO (-2590 4085);
FORCEPROP 1 LAST TOLERANCE 20%
J 0
(-2550 4200);
DISPLAY 0.510638 (-2550 4200);
FORCEPROP 1 LAST PACK_TYPE SMLF
J 0
(-2550 4050);
DISPLAY 0.510638 (-2550 4050);
FORCEPROP 1 LAST VALUE 390UF
J 0
(-2550 4250);
DISPLAY 0.510638 (-2550 4250);
FORCEPROP 1 LAST VOLTAGE 2.5V
J 0
(-2550 4150);
DISPLAY 0.510638 (-2550 4150);
FORCEPROP 1 LAST MATERIAL ALUM
J 0
(-2550 4100);
DISPLAY 0.510638 (-2550 4100);
FORCEPROP 1 LAST PATH I94
J 0
(-2550 4350);
DISPLAY 0.978723 (-2550 4350);
DISPLAY INVISIBLE (-2550 4350);
FORCEPROP 1 LAST PART_NUMBER CC7390JMZ13
J 0
(-2550 4000);
DISPLAY 0.510638 (-2550 4000);
DISPLAY INVISIBLE (-2550 4000);
FORCEPROP 2 LAST CDS_LIB pure_quanta
J 0
(-2600 4200);
DISPLAY INVISIBLE (-2600 4200);
FORCEADD Q_CAPP..1
(-2325 4200);
FORCEPROP 1 LAST LOCATION PC6630
J 0
(-2275 4300);
DISPLAY 0.638298 (-2275 4300);
FORCEPROP 0 LAST $SEC 1
J 0
(-2275 4350);
DISPLAY 0.680851 (-2275 4350);
PAINT MONO (-2275 4350);
DISPLAY INVISIBLE (-2275 4350);
FORCEPROP 0 LAST CDS_SEC 1
J 0
(-2275 4350);
DISPLAY 0.680851 (-2275 4350);
DISPLAY INVISIBLE (-2275 4350);
FORCEPROP 1 LASTPIN (-2325 4300) $PN 1
J 0
(-2315 4285);
DISPLAY 0.787234 (-2315 4285);
PAINT MONO (-2315 4285);
FORCEPROP 1 LASTPIN (-2325 4100) $PN 2
J 0
(-2315 4085);
DISPLAY 0.787234 (-2315 4085);
PAINT MONO (-2315 4085);
FORCEPROP 1 LAST TOLERANCE 20%
J 0
(-2275 4200);
DISPLAY 0.510638 (-2275 4200);
FORCEPROP 1 LAST PACK_TYPE SMLF
J 0
(-2275 4050);
DISPLAY 0.510638 (-2275 4050);
FORCEPROP 1 LAST VALUE 390UF
J 0
(-2275 4250);
DISPLAY 0.510638 (-2275 4250);
FORCEPROP 1 LAST VOLTAGE 2.5V
J 0
(-2275 4150);
DISPLAY 0.510638 (-2275 4150);
FORCEPROP 1 LAST MATERIAL ALUM
J 0
(-2275 4100);
DISPLAY 0.510638 (-2275 4100);
FORCEPROP 1 LAST PATH I95
J 0
(-2275 4350);
DISPLAY 0.978723 (-2275 4350);
DISPLAY INVISIBLE (-2275 4350);
FORCEPROP 1 LAST PART_NUMBER CC7390JMZ13
J 0
(-2275 4000);
DISPLAY 0.510638 (-2275 4000);
DISPLAY INVISIBLE (-2275 4000);
FORCEPROP 2 LAST CDS_LIB pure_quanta
J 0
(-2325 4200);
DISPLAY INVISIBLE (-2325 4200);
FORCEADD UNIVERSAL_GND..1
(-2000 3875);
FORCEPROP 3 LASTPIN (-2000 3925) SIG_NAME GND\g
J 0
(-1990 3935);
DISPLAY 0.659574 (-1990 3935);
PAINT MONO (-1990 3935);
DISPLAY INVISIBLE (-1990 3935);
FORCEPROP 1 LAST PATH I96
J 0
(-1925 3875);
DISPLAY 0.872340 (-1925 3875);
PAINT AQUA (-1925 3875);
DISPLAY INVISIBLE (-1925 3875);
FORCEPROP 1 LAST HDL_POWER GND
J 1
(-1975 3800);
DISPLAY 0.872340 (-1975 3800);
PAINT GREEN (-1975 3800);
DISPLAY INVISIBLE (-1975 3800);
FORCEPROP 2 LAST CDS_LIB pure_quanta_power
J 0
(-2000 3875);
DISPLAY INVISIBLE (-2000 3875);
FORCEADD Q_RES..2
(-2000 4175);
FORCEPROP 1 LAST LOCATION PR6625
J 0
(-1955 4300);
DISPLAY 0.787234 (-1955 4300);
FORCEPROP 0 LAST $SEC 1
J 0
(-1950 4350);
DISPLAY 0.680851 (-1950 4350);
PAINT MONO (-1950 4350);
DISPLAY INVISIBLE (-1950 4350);
FORCEPROP 0 LAST CDS_SEC 1
J 0
(-1950 4350);
DISPLAY 0.680851 (-1950 4350);
DISPLAY INVISIBLE (-1950 4350);
FORCEPROP 1 LASTPIN (-2000 4275) $PN 1
J 0
(-1995 4237);
DISPLAY 0.787234 (-1995 4237);
PAINT MONO (-1995 4237);
FORCEPROP 1 LASTPIN (-2000 4075) $PN 2
J 0
(-1995 4085);
DISPLAY 0.787234 (-1995 4085);
PAINT MONO (-1995 4085);
FORCEPROP 1 LAST PACK_TYPE 0603LF
J 0
(-1960 4000);
DISPLAY 0.638298 (-1960 4000);
FORCEPROP 1 LAST VALUE 499
J 0
(-1955 4250);
DISPLAY 0.638298 (-1955 4250);
FORCEPROP 1 LAST TOLERANCE 1%
J 0
(-1955 4200);
DISPLAY 0.638298 (-1955 4200);
FORCEPROP 1 LAST MATERIAL CHIP
J 0
(-1960 4100);
DISPLAY 0.638298 (-1960 4100);
FORCEPROP 1 LAST WATTAGE 1/10W
J 0
(-1960 4150);
DISPLAY 0.638298 (-1960 4150);
FORCEPROP 1 LAST PATH I97
J 0
(-1950 4350);
DISPLAY 0.978723 (-1950 4350);
PAINT WHITE (-1950 4350);
DISPLAY INVISIBLE (-1950 4350);
FORCEPROP 1 LAST PART_NUMBER CS14993F901
J 0
(-1960 4050);
DISPLAY 0.638298 (-1960 4050);
DISPLAY INVISIBLE (-1960 4050);
FORCEPROP 2 LAST CDS_LIB pure_quanta
J 0
(-2000 4175);
DISPLAY INVISIBLE (-2000 4175);
FORCEADD VCC15..1
(-1375 4675);
FORCEPROP 3 LASTPIN (-1375 4625) SIG_NAME P0V9_CPU1_RT_2D\g
J 0
(-1365 4635);
DISPLAY 0.659574 (-1365 4635);
PAINT MONO (-1365 4635);
DISPLAY INVISIBLE (-1365 4635);
FORCEPROP 1 LAST HDL_POWER P0V9_CPU1_RT_2D
J 1
(-1375 4725);
DISPLAY 0.617021 (-1375 4725);
PAINT GREEN (-1375 4725);
FORCEPROP 1 LAST PATH I98
J 0
(-1325 4700);
DISPLAY 0.872340 (-1325 4700);
PAINT AQUA (-1325 4700);
DISPLAY INVISIBLE (-1325 4700);
FORCEPROP 2 LAST CDS_LIB pure_quanta_power
J 0
(-1375 4675);
DISPLAY INVISIBLE (-1375 4675);
FORCEPROP 2 LAST BOM_COST VR_DIMM 
J 0
(-1375 4775);
DISPLAY 0.680851 (-1375 4775);
DISPLAY INVISIBLE (-1375 4775);
FORCEADD UNIVERSAL_GND..1
(-2775 4875);
FORCEPROP 3 LASTPIN (-2775 4925) SIG_NAME GND\g
J 0
(-2765 4935);
DISPLAY 0.659574 (-2765 4935);
PAINT MONO (-2765 4935);
DISPLAY INVISIBLE (-2765 4935);
FORCEPROP 1 LAST PATH I99
J 0
(-2700 4875);
DISPLAY 0.872340 (-2700 4875);
PAINT AQUA (-2700 4875);
DISPLAY INVISIBLE (-2700 4875);
FORCEPROP 1 LAST HDL_POWER GND
J 1
(-2750 4800);
DISPLAY 0.872340 (-2750 4800);
PAINT GREEN (-2750 4800);
DISPLAY INVISIBLE (-2750 4800);
FORCEPROP 2 LAST CDS_LIB pure_quanta_power
J 0
(-2775 4875);
DISPLAY INVISIBLE (-2775 4875);
FORCEADD DNS..2
(-8850 3775);
PAINT RED (-8850 3775);
FORCEPROP 1 LAST COMMENT_BODY TRUE
R 1
J 0
(-8775 3550);
DISPLAY 0.872340 (-8775 3550);
PAINT GREEN (-8775 3550);
DISPLAY INVISIBLE (-8775 3550);
FORCEPROP 2 LAST CDS_LIB mstr_misc
J 0
(-8850 3775);
DISPLAY INVISIBLE (-8850 3775);
FORCEPROP 2 LAST BOM_COST VR_DIMM 
J 0
(-9200 3900);
DISPLAY 0.680851 (-9200 3900);
DISPLAY INVISIBLE (-9200 3900);
FORCEADD DNS..2
(-8725 875);
PAINT RED (-8725 875);
FORCEPROP 1 LAST COMMENT_BODY TRUE
R 1
J 0
(-8650 650);
DISPLAY 0.872340 (-8650 650);
PAINT GREEN (-8650 650);
DISPLAY INVISIBLE (-8650 650);
FORCEPROP 2 LAST CDS_LIB mstr_misc
J 0
(-8725 875);
DISPLAY INVISIBLE (-8725 875);
FORCEPROP 2 LAST BOM_COST VR_DIMM 
J 0
(-9075 1000);
DISPLAY 0.680851 (-9075 1000);
DISPLAY INVISIBLE (-9075 1000);
FORCEADD DNS..1
(-5450 3650);
PAINT RED (-5450 3650);
FORCEPROP 1 LAST COMMENT_BODY TRUE
R 1
J 0
(-5375 3425);
DISPLAY 0.872340 (-5375 3425);
PAINT GREEN (-5375 3425);
DISPLAY INVISIBLE (-5375 3425);
FORCEPROP 2 LAST CDS_LIB mstr_misc
J 0
(-5450 3650);
DISPLAY INVISIBLE (-5450 3650);
FORCEADD DNS..1
(-5425 1250);
PAINT RED (-5425 1250);
FORCEPROP 1 LAST COMMENT_BODY TRUE
R 1
J 0
(-5350 1025);
DISPLAY 0.872340 (-5350 1025);
PAINT GREEN (-5350 1025);
DISPLAY INVISIBLE (-5350 1025);
FORCEPROP 2 LAST CDS_LIB mstr_misc
J 0
(-5425 1250);
DISPLAY INVISIBLE (-5425 1250);
FORCEADD DNS..1
(-5400 750);
PAINT RED (-5400 750);
FORCEPROP 1 LAST COMMENT_BODY TRUE
R 1
J 0
(-5325 525);
DISPLAY 0.872340 (-5325 525);
PAINT GREEN (-5325 525);
DISPLAY INVISIBLE (-5325 525);
FORCEPROP 2 LAST CDS_LIB mstr_misc
J 0
(-5400 750);
DISPLAY INVISIBLE (-5400 750);
FORCEADD DNS..1
(-5450 4125);
PAINT RED (-5450 4125);
FORCEPROP 1 LAST COMMENT_BODY TRUE
R 1
J 0
(-5375 3900);
DISPLAY 0.872340 (-5375 3900);
PAINT GREEN (-5375 3900);
DISPLAY INVISIBLE (-5375 3900);
FORCEPROP 2 LAST CDS_LIB mstr_misc
J 0
(-5450 4125);
DISPLAY INVISIBLE (-5450 4125);
FORCEADD DNS..1
(-8500 6125);
PAINT RED (-8500 6125);
FORCEPROP 1 LAST COMMENT_BODY TRUE
R 1
J 0
(-8425 5900);
DISPLAY 0.872340 (-8425 5900);
PAINT GREEN (-8425 5900);
DISPLAY INVISIBLE (-8425 5900);
FORCEPROP 2 LAST CDS_LIB mstr_misc
J 0
(-8500 6125);
DISPLAY INVISIBLE (-8500 6125);
FORCEADD QUANTA_TITLE_BLOCK_C..1
(-575 25);
FORCEPROP 0 LAST CDS_CON_LAST_MODIFIED Thu Sep 14 16:13:03 2023
J 0
(-2460 40);
DISPLAY INVISIBLE (-2460 40);
FORCEPROP 1 LAST CUSTOM_TXT_CDS <CON_LAST_MODIFIED>
J 0
(-2460 40);
DISPLAY 0.978723 (-2460 40);
FORCEPROP 2 LAST CUSTOM_TXT_CDS <XR_PAGE_TITLE>
J 0
(-8465 5275);
DISPLAY 0.638298 (-8465 5275);
PAINT PINK (-8465 5275);
DISPLAY INVISIBLE (-8465 5275);
FORCEPROP 1 LAST CUSTOM_TXT_CDS <NAME_2>
J 0
(-3750 75);
FORCEPROP 1 LAST CUSTOM_TXT_CDS <NAME_1>
J 0
(-3750 200);
FORCEPROP 1 LAST CUSTOM_TXT_CDS <Q_NUMBER>
J 0
(-1978 128);
DISPLAY 1.212766 (-1978 128);
FORCEPROP 1 LAST CUSTOM_TXT_CDS <Q_PROJ>
J 0
(-2957 127);
DISPLAY 1.212766 (-2957 127);
FORCEPROP 1 LAST CUSTOM_TXT_CDS <Q_REV>
J 0
(-759 128);
DISPLAY 1.212766 (-759 128);
FORCEPROP 1 LAST CUSTOM_TXT_CDS <CON_PAGE_NUM> OF <CON_TOTAL_PAGES>
J 0
(-1021 43);
DISPLAY 0.978723 (-1021 43);
FORCEPROP 1 LAST Q_TITLE P0V9_CPU1_RT_2D VR  PHASE1 & 2
J 0
(-9941 51);
DISPLAY 2.446809 (-9941 51);
PAINT GREEN (-9941 51);
FORCEPROP 1 LAST Q_DEPT CCBU
J 1
(-4338 74);
DISPLAY 1.957447 (-4338 74);
PAINT GREEN (-4338 74);
DISPLAY INVISIBLE (-4338 74);
FORCEPROP 1 LAST COMMENT_BODY TRUE
J 0
(-563 12);
DISPLAY 0.978723 (-563 12);
PAINT GREEN (-563 12);
DISPLAY INVISIBLE (-563 12);
FORCEPROP 2 LAST CDS_LIB pure_quanta
J 0
(-575 25);
DISPLAY INVISIBLE (-575 25);
FORCEPROP 1 LAST CDS_LMAN_SYM_OUTLINE -9475,6775,100,-125
J 0
(-575 25);
DISPLAY 0.468085 (-575 25);
PAINT GREEN (-575 25);
DISPLAY INVISIBLE (-575 25);
FORCEPROP 2 LAST PAGE_BORDER TRUE
J 0
(-8465 5275);
DISPLAY 0.638298 (-8465 5275);
PAINT PINK (-8465 5275);
DISPLAY INVISIBLE (-8465 5275);
FORCEPROP 2 LAST BOM_COST VR_DIMM 
J 0
(-3750 225);
DISPLAY 0.680851 (-3750 225);
DISPLAY INVISIBLE (-3750 225);
FORCEPROP 2 LAST CDS_XR_PAGE_TITLE CR-366 : @T6G_MB_LIB.T6G(SCH_1):PAGE366
J 0
(-8465 5275);
DISPLAY 0.638298 (-8465 5275);
PAINT PINK (-8465 5275);
DISPLAY INVISIBLE (-8465 5275);
WIRE 16 -1 (-9500 875)(-9500 925);
WIRE 16 -1 (-2375 5025)(-2375 4900);
WIRE 16 -1 (-950 5325)(-950 5525);
WIRE 16 -1 (-950 5325)(-950 5225);
WIRE 16 -1 (-1725 5325)(-950 5325);
WIRE 16 -1 (-5425 3525)(-5425 3450);
WIRE 16 -1 (-5400 625)(-5400 550);
WIRE 16 -1 (-950 5025)(-950 4850);
WIRE 16 -1 (-8050 2300)(-8050 2200);
WIRE 16 -1 (-5850 2025)(-5850 2150);
WIRE 16 -1 (-5350 2150)(-5350 2025);
WIRE 16 -1 (-4850 2025)(-4850 2150);
WIRE 16 -1 (-4350 2025)(-4350 2150);
WIRE 16 -1 (-3875 2025)(-3875 2150);
WIRE 16 -1 (-3500 2150)(-3500 2025);
WIRE 16 -1 (-3100 2100)(-3100 2025);
WIRE 16 -1 (-8700 800)(-8700 700);
WIRE 16 -1 (-9625 3775)(-9625 3825);
WIRE 16 -1 (-9425 6400)(-9425 6250);
WIRE 16 -1 (-8825 3700)(-8825 3600);
WIRE 16 -1 (-8875 4625)(-8875 4675);
WIRE 16 -1 (-8175 5200)(-8175 5100);
WIRE 16 -1 (-8525 6400)(-8525 6250);
WIRE 16 -1 (-5975 4925)(-5975 5050);
WIRE 16 -1 (-5475 5050)(-5475 4925);
WIRE 16 -1 (-4975 4925)(-4975 5050);
WIRE 16 -1 (-4475 4925)(-4475 5050);
WIRE 16 -1 (-4000 4925)(-4000 5050);
WIRE 16 -1 (-3625 5050)(-3625 4925);
WIRE 16 -1 (-3225 5000)(-3225 4925);
WIRE 16 -1 (-2650 2100)(-2650 2025);
WIRE 16 -1 (-2250 2125)(-2250 2000);
WIRE 16 -1 (-8750 1725)(-8750 1775);
WIRE 16 -1 (-2775 5000)(-2775 4925);
WIRE 16 -1 (-6350 5000)(-6350 5325);
WIRE 16 -1 (-6350 5000)(-6350 4950);
WIRE 16 -1 (-6350 5000)(-6675 5000);
WIRE 16 -1 (-6350 5325)(-5975 5325);
WIRE 16 -1 (-5975 5325)(-5475 5325);
WIRE 16 -1 (-5975 5325)(-5975 5250);
WIRE 16 -1 (-6350 4950)(-6675 4950);
WIRE 16 -1 (-4975 5325)(-5475 5325);
WIRE 16 -1 (-5475 5250)(-5475 5325);
WIRE 16 -1 (-4975 5325)(-4475 5325);
WIRE 16 -1 (-4975 5250)(-4975 5325);
WIRE 16 -1 (-4475 5325)(-4000 5325);
WIRE 16 -1 (-4475 5250)(-4475 5325);
WIRE 16 -1 (-4000 5325)(-3625 5325);
WIRE 16 -1 (-4000 5250)(-4000 5325);
WIRE 16 -1 (-3625 5325)(-3225 5325);
WIRE 16 -1 (-3625 5250)(-3625 5325);
WIRE 16 -1 (-3225 5325)(-2775 5325);
WIRE 16 -1 (-3225 5200)(-3225 5325);
WIRE 16 -1 (-2775 5325)(-2425 5325);
WIRE 16 -1 (-2775 5200)(-2775 5325);
WIRE 16 -1 (-2425 5500)(-2425 5325);
WIRE 16 -1 (-2425 5325)(-2375 5325);
WIRE 16 -1 (-1925 5325)(-2375 5325);
WIRE 16 -1 (-2375 5225)(-2375 5325);
WIRE 16 -1 (-8525 6050)(-8525 5900);
WIRE 16 -1 (-8525 5900)(-8875 5900);
WIRE 16 -1 (-8875 5500)(-8875 5900);
WIRE 16 -1 (-8875 5900)(-9425 5900);
WIRE 16 -1 (-9425 5900)(-9425 6050);
WIRE 16 -1 (-8350 5500)(-8875 5500);
WIRE 16 -1 (-8875 5500)(-8875 5400);
WIRE 16 -1 (-8175 5500)(-8350 5500);
WIRE 16 -1 (-8350 5625)(-8350 5500);
WIRE 16 -1 (-7625 5500)(-8175 5500);
WIRE 16 -1 (-8175 5500)(-8175 5400);
WIRE 16 -1 (-7625 5000)(-7625 5500);
WIRE 16 -1 (-7625 5000)(-7525 5000);
WIRE 16 -1 (-6550 1000)(-6375 1000);
WIRE 16 -1 (-6375 1000)(-6375 950);
WIRE 16 -1 (-6375 950)(-6375 900);
WIRE 16 -1 (-6550 950)(-6375 950);
WIRE 16 -1 (-6375 900)(-6375 850);
WIRE 16 -1 (-6550 900)(-6375 900);
WIRE 16 -1 (-6550 850)(-6375 850);
WIRE 16 -1 (-6375 850)(-6375 700);
WIRE 16 -1 (-7500 2100)(-7500 2600);
WIRE 16 -1 (-7500 2100)(-7400 2100);
WIRE 16 -1 (-7500 2600)(-8050 2600);
WIRE 16 -1 (-8050 2600)(-8050 2500);
WIRE 16 -1 (-8050 2600)(-8750 2600);
WIRE 16 -1 (-8750 2600)(-8750 3000);
WIRE 16 -1 (-8750 2600)(-8750 2500);
WIRE 16 -1 (-6675 3900)(-6500 3900);
WIRE 16 -1 (-6500 3900)(-6500 3850);
WIRE 16 -1 (-6500 3850)(-6500 3800);
WIRE 16 -1 (-6675 3850)(-6500 3850);
WIRE 16 -1 (-6500 3800)(-6500 3750);
WIRE 16 -1 (-6675 3800)(-6500 3800);
WIRE 16 -1 (-6675 3750)(-6500 3750);
WIRE 16 -1 (-6500 3750)(-6500 3600);
WIRE 16 -1 (-6225 2100)(-6225 2050);
WIRE 16 -1 (-6225 2100)(-6225 2425);
WIRE 16 -1 (-6225 2100)(-6550 2100);
WIRE 16 -1 (-6225 2050)(-6550 2050);
WIRE 16 -1 (-6225 2425)(-5850 2425);
WIRE 16 -1 (-5850 2425)(-5350 2425);
WIRE 16 -1 (-5850 2425)(-5850 2350);
WIRE 16 -1 (-4850 2425)(-5350 2425);
WIRE 16 -1 (-5350 2350)(-5350 2425);
WIRE 16 -1 (-4850 2425)(-4350 2425);
WIRE 16 -1 (-4850 2350)(-4850 2425);
WIRE 16 -1 (-4350 2425)(-3875 2425);
WIRE 16 -1 (-4350 2350)(-4350 2425);
WIRE 16 -1 (-3875 2425)(-3500 2425);
WIRE 16 -1 (-3875 2350)(-3875 2425);
WIRE 16 -1 (-3500 2425)(-3100 2425);
WIRE 16 -1 (-3500 2350)(-3500 2425);
WIRE 16 -1 (-3100 2425)(-2650 2425);
WIRE 16 -1 (-3100 2300)(-3100 2425);
WIRE 16 -1 (-2650 2425)(-2300 2425);
WIRE 16 -1 (-2650 2300)(-2650 2425);
WIRE 16 -1 (-2300 2600)(-2300 2425);
WIRE 16 -1 (-2300 2425)(-2250 2425);
WIRE 16 -1 (-2250 2325)(-2250 2425);
WIRE 16 -1 (-3675 1075)(-3450 1075);
WIRE 16 -1 (-3675 1075)(-3675 1200);
WIRE 16 -1 (-3675 1075)(-4000 1075);
WIRE 16 -1 (-3450 1075)(-3225 1075);
WIRE 16 -1 (-3450 1200)(-3450 1075);
WIRE 16 -1 (-3000 1075)(-3225 1075);
WIRE 16 -1 (-3225 1200)(-3225 1075);
WIRE 16 -1 (-4000 1075)(-4000 1200);
WIRE 16 -1 (-2800 1075)(-3000 1075);
WIRE 16 -1 (-3000 1200)(-3000 1075);
WIRE 16 -1 (-2800 1075)(-2475 1075);
WIRE 16 -1 (-2800 1200)(-2800 1075);
WIRE 16 -1 (-2475 1075)(-2225 1075);
WIRE 16 -1 (-2475 1200)(-2475 1075);
WIRE 16 -1 (-2225 1200)(-2225 1075);
WIRE 16 -1 (-2225 1075)(-2225 1000);
WIRE 16 -1 (-4000 1450)(-4250 1450);
WIRE 16 -1 (-3675 1450)(-4000 1450);
WIRE 16 -1 (-4000 1400)(-4000 1450);
WIRE 16 -1 (-4675 1450)(-4250 1450);
WIRE 16 -1 (-4250 1450)(-4250 375);
WIRE 16 -1 (-4250 375)(-4925 375);
WIRE 16 -1 (-3675 1450)(-3450 1450);
WIRE 16 -1 (-3675 1450)(-3675 1400);
WIRE 16 -1 (-3450 1450)(-3225 1450);
WIRE 16 -1 (-3450 1450)(-3450 1400);
WIRE 16 -1 (-3000 1450)(-3225 1450);
WIRE 16 -1 (-3225 1450)(-3225 1400);
WIRE 16 -1 (-2800 1450)(-3000 1450);
WIRE 16 -1 (-3000 1400)(-3000 1450);
WIRE 16 -1 (-2800 1450)(-2475 1450);
WIRE 16 -1 (-2800 1450)(-2800 1400);
WIRE 16 -1 (-2225 1450)(-2475 1450);
WIRE 16 -1 (-2475 1400)(-2475 1450);
WIRE 16 -1 (-2225 1450)(-1250 1450);
WIRE 16 -1 (-2225 1450)(-2225 1400);
WIRE 16 -1 (-1250 1450)(-1250 1725);
WIRE 16 -1 (-3800 3975)(-3800 4100);
WIRE 16 -1 (-3800 3975)(-3575 3975);
WIRE 16 -1 (-3800 3975)(-4125 3975);
WIRE 16 -1 (-4125 3975)(-4125 4100);
WIRE 16 -1 (-3575 4100)(-3575 3975);
WIRE 16 -1 (-3575 3975)(-3350 3975);
WIRE 16 -1 (-3350 4100)(-3350 3975);
WIRE 16 -1 (-3125 3975)(-3350 3975);
WIRE 16 -1 (-3125 4100)(-3125 3975);
WIRE 16 -1 (-2925 3975)(-3125 3975);
WIRE 16 -1 (-2925 4100)(-2925 3975);
WIRE 16 -1 (-2925 3975)(-2600 3975);
WIRE 16 -1 (-2600 4100)(-2600 3975);
WIRE 16 -1 (-2600 3975)(-2325 3975);
WIRE 16 -1 (-2325 4100)(-2325 3975);
WIRE 16 -1 (-2000 3975)(-2325 3975);
WIRE 16 -1 (-2000 4075)(-2000 3975);
WIRE 16 -1 (-2000 3975)(-2000 3925);
WIRE 16 -1 (-4125 4350)(-4350 4350);
WIRE 16 -1 (-3800 4350)(-4125 4350);
WIRE 16 -1 (-4125 4300)(-4125 4350);
WIRE 16 -1 (-4800 4350)(-4350 4350);
WIRE 16 -1 (-4350 4350)(-4350 3200);
WIRE 16 -1 (-4350 3200)(-5000 3200);
WIRE 16 -1 (-3800 4350)(-3575 4350);
WIRE 16 -1 (-3800 4350)(-3800 4300);
WIRE 16 -1 (-3575 4350)(-3350 4350);
WIRE 16 -1 (-3575 4350)(-3575 4300);
WIRE 16 -1 (-3125 4350)(-3350 4350);
WIRE 16 -1 (-3350 4350)(-3350 4300);
WIRE 16 -1 (-2925 4350)(-3125 4350);
WIRE 16 -1 (-3125 4300)(-3125 4350);
WIRE 16 -1 (-2925 4350)(-2600 4350);
WIRE 16 -1 (-2925 4350)(-2925 4300);
WIRE 16 -1 (-2600 4350)(-2325 4350);
WIRE 16 -1 (-2600 4300)(-2600 4350);
WIRE 16 -1 (-2325 4350)(-2000 4350);
WIRE 16 -1 (-2325 4350)(-2325 4300);
WIRE 16 -1 (-1375 4350)(-2000 4350);
WIRE 16 -1 (-2000 4350)(-2000 4275);
WIRE 16 -1 (-1375 4350)(-1375 4625);
WIRE 16 -1 (-7525 4350)(-9375 4350);
FORCEPROP 2 LAST SIG_NAME P0V9_RETIMER_CPU1_IMON1
J 0
(-8335 4360);
DISPLAY 0.617021 (-8335 4360);
WIRE 16 -1 (-4000 4700)(-3875 4700);
WIRE 16 -1 (-3875 4700)(-3875 4450);
WIRE 16 -1 (-6675 4450)(-3875 4450);
FORCEPROP 2 LAST SIG_NAME SW_P0V9_RETIMER_CPU1_PH1
J 0
(-6510 4460);
DISPLAY 0.617021 (-6510 4460);
FORCEPROP 2 LASTPROP $XRERR UNIQUE?
J 0
(-6750 4460);
DISPLAY 0.638298 (-6750 4460);
PAINT MONO (-6750 4460);
DISPLAY INVISIBLE (-6750 4460);
WIRE 16 -1 (-5375 4700)(-4200 4700);
FORCEPROP 2 LAST SIG_NAME SW_P0V9_RETIMER_CPU1_BOOT1_RC
J 0
(-5160 4710);
DISPLAY 0.617021 (-5160 4710);
FORCEPROP 2 LASTPROP $XRERR UNIQUE?
J 0
(-5400 4710);
DISPLAY 0.638298 (-5400 4710);
PAINT MONO (-5400 4710);
DISPLAY INVISIBLE (-5400 4710);
WIRE 16 -1 (-7525 4500)(-7625 4500);
WIRE 16 -1 (-7625 4700)(-7625 4500);
WIRE 16 -1 (-7625 4700)(-7625 4950);
WIRE 16 -1 (-7525 4700)(-7625 4700);
WIRE 16 -1 (-7625 4950)(-8875 4950);
FORCEPROP 2 LAST SIG_NAME P0V9_RETIMER_CPU1_VCC1
J 0
(-8310 4960);
DISPLAY 0.617021 (-8310 4960);
FORCEPROP 2 LASTPROP $XRERR UNIQUE?
J 0
(-8550 4960);
DISPLAY 0.638298 (-8550 4960);
PAINT MONO (-8550 4960);
DISPLAY INVISIBLE (-8550 4960);
WIRE 16 -1 (-8875 5200)(-8875 4950);
WIRE 16 -1 (-8875 4950)(-8875 4875);
WIRE 16 -1 (-6675 4700)(-5575 4700);
FORCEPROP 2 LAST SIG_NAME SW_P0V9_RETIMER_CPU1_BOOT1
J 0
(-6510 4710);
DISPLAY 0.617021 (-6510 4710);
FORCEPROP 2 LASTPROP $XRERR UNIQUE?
J 0
(-6750 4710);
DISPLAY 0.638298 (-6750 4710);
PAINT MONO (-6750 4710);
DISPLAY INVISIBLE (-6750 4710);
WIRE 16 -1 (-5975 4000)(-6675 4000);
FORCEPROP 2 LAST SIG_NAME NC_PV09_RETIMER_CPU1_GL2_1
J 0
(-6585 4010);
DISPLAY 0.617021 (-6585 4010);
FORCEPROP 2 LASTPROP $XRERR UNIQUE?
J 0
(-5945 4000);
DISPLAY 0.638298 (-5945 4000);
PAINT MONO (-5945 4000);
DISPLAY INVISIBLE (-5945 4000);
WIRE 16 -1 (-8700 1150)(-7400 1150);
FORCEPROP 0 LAST SIG_NAME P0V9_RETIMER_CPU1_LSET2
J 0
(-8260 1160);
DISPLAY 0.617021 (-8260 1160);
FORCEPROP 2 LASTPROP $XRERR UNIQUE?
J 0
(-8500 1160);
DISPLAY 0.638298 (-8500 1160);
PAINT MONO (-8500 1160);
DISPLAY INVISIBLE (-8500 1160);
WIRE 16 -1 (-8700 1150)(-8700 1000);
WIRE 16 -1 (-8200 950)(-7400 950);
FORCEPROP 2 LAST SIG_NAME P0V9_RETIMER_CPU1_TEMP0
J 0
(-8185 960);
DISPLAY 0.617021 (-8185 960);
WIRE 16 -1 (-8175 850)(-7400 850);
FORCEPROP 2 LAST SIG_NAME P0V9_RETIMER_CPU1_PWM2
J 0
(-8185 860);
DISPLAY 0.617021 (-8185 860);
WIRE 16 -1 (-3875 1800)(-3750 1800);
WIRE 16 -1 (-3750 1800)(-3750 1550);
WIRE 16 -1 (-6550 1550)(-3750 1550);
FORCEPROP 2 LAST SIG_NAME SW_P0V9_RETIMER_CPU1_PH2
J 0
(-6385 1560);
DISPLAY 0.617021 (-6385 1560);
FORCEPROP 2 LASTPROP $XRERR UNIQUE?
J 0
(-6625 1560);
DISPLAY 0.638298 (-6625 1560);
PAINT MONO (-6625 1560);
DISPLAY INVISIBLE (-6625 1560);
WIRE 16 -1 (-5650 375)(-5650 1200);
WIRE 16 -1 (-5125 375)(-5650 375);
WIRE 16 -1 (-5650 1200)(-6550 1200);
FORCEPROP 2 LAST SIG_NAME P0V9_RETIMER_CPU1_VOS2
J 0
(-6460 1210);
DISPLAY 0.617021 (-6460 1210);
FORCEPROP 2 LASTPROP $XRERR UNIQUE?
J 0
(-6700 1210);
DISPLAY 0.638298 (-6700 1210);
PAINT MONO (-6700 1210);
DISPLAY INVISIBLE (-6700 1210);
WIRE 16 -1 (-7400 1200)(-8100 1200);
FORCEPROP 2 LAST SIG_NAME NC_PV09_RETIMER_CPU1_DNC2
J 0
(-8310 1210);
DISPLAY 0.617021 (-8310 1210);
FORCEPROP 2 LASTPROP $XRERR UNIQUE?
J 0
(-8340 1200);
DISPLAY 0.638298 (-8340 1200);
PAINT MONO (-8340 1200);
DISPLAY INVISIBLE (-8340 1200);
WIRE 16 -1 (-9500 1125)(-9500 1275);
WIRE 16 -1 (-8100 1275)(-9500 1275);
WIRE 16 -1 (-8100 1350)(-8100 1275);
WIRE 16 -1 (-7400 1350)(-8100 1350);
WIRE 16 -1 (-8100 1350)(-8731 1350);
FORCEPROP 2 LAST SIG_NAME PV09_RETIMER_CPU1_VCCS
J 0
(-8210 1360);
DISPLAY 0.617021 (-8210 1360);
WIRE 16 -1 (-7400 1450)(-9250 1450);
FORCEPROP 2 LAST SIG_NAME P0V9_RETIMER_CPU1_IMON2
J 0
(-8235 1460);
DISPLAY 0.617021 (-8235 1460);
WIRE 16 -1 (-7400 1600)(-7500 1600);
WIRE 16 -1 (-7500 1800)(-7500 1600);
WIRE 16 -1 (-7500 1800)(-7500 2050);
WIRE 16 -1 (-7400 1800)(-7500 1800);
WIRE 16 -1 (-7500 2050)(-8750 2050);
FORCEPROP 2 LAST SIG_NAME P0V9_RETIMER_CPU1_VCC2
J 0
(-8235 2060);
DISPLAY 0.617021 (-8235 2060);
FORCEPROP 2 LASTPROP $XRERR UNIQUE?
J 0
(-8475 2060);
DISPLAY 0.638298 (-8475 2060);
PAINT MONO (-8475 2060);
DISPLAY INVISIBLE (-8475 2060);
WIRE 16 -1 (-8750 2300)(-8750 2050);
WIRE 16 -1 (-8750 2050)(-8750 1975);
WIRE 16 -1 (-5775 4100)(-6675 4100);
FORCEPROP 2 LAST SIG_NAME P0V9_RETIMER_CPU1_VOS1
J 0
(-6585 4110);
DISPLAY 0.617021 (-6585 4110);
FORCEPROP 2 LASTPROP $XRERR UNIQUE?
J 0
(-6825 4110);
DISPLAY 0.638298 (-6825 4110);
PAINT MONO (-6825 4110);
DISPLAY INVISIBLE (-6825 4110);
WIRE 16 -1 (-5775 3200)(-5775 4100);
WIRE 16 -1 (-5200 3200)(-5775 3200);
WIRE 16 -1 (-5425 4050)(-5425 3725);
FORCEPROP 2 LAST SIG_NAME SW_P0V9_RETIMER_CPU1_SW1_RC
J 0
(-5385 3860);
DISPLAY 0.489362 (-5385 3860);
FORCEPROP 2 LASTPROP $XRERR UNIQUE?
J 0
(-5625 3860);
DISPLAY 0.638298 (-5625 3860);
PAINT MONO (-5625 3860);
DISPLAY INVISIBLE (-5625 3860);
WIRE 16 -1 (-8825 4050)(-7525 4050);
FORCEPROP 0 LAST SIG_NAME P0V9_RETIMER_CPU1_LSET1
J 0
(-8335 4060);
DISPLAY 0.617021 (-8335 4060);
FORCEPROP 2 LASTPROP $XRERR UNIQUE?
J 0
(-8575 4060);
DISPLAY 0.638298 (-8575 4060);
PAINT MONO (-8575 4060);
DISPLAY INVISIBLE (-8575 4060);
WIRE 16 -1 (-8825 4050)(-8825 3900);
WIRE 16 -1 (-8325 3850)(-7525 3850);
FORCEPROP 2 LAST SIG_NAME P0V9_RETIMER_CPU1_TEMP0
J 0
(-8335 3860);
DISPLAY 0.617021 (-8335 3860);
WIRE 16 -1 (-7525 4250)(-8225 4250);
WIRE 16 -1 (-8225 4250)(-8225 4175);
WIRE 16 -1 (-8225 4250)(-8856 4250);
WIRE 16 -1 (-8225 4175)(-9625 4175);
WIRE 16 -1 (-9625 4025)(-9625 4175);
WIRE 16 -1 (-5400 1150)(-5400 825);
FORCEPROP 2 LAST SIG_NAME SW_P0V9_RETIMER_CPU1_SW2_RC
J 0
(-5360 960);
DISPLAY 0.489362 (-5360 960);
FORCEPROP 2 LASTPROP $XRERR UNIQUE?
J 0
(-5600 960);
DISPLAY 0.638298 (-5600 960);
PAINT MONO (-5600 960);
DISPLAY INVISIBLE (-5600 960);
WIRE 16 -1 (-7525 4100)(-8225 4100);
FORCEPROP 2 LAST SIG_NAME NC_PV09_RETIMER_CPU1_DNC1
J 0
(-8385 4110);
DISPLAY 0.617021 (-8385 4110);
FORCEPROP 2 LASTPROP $XRERR UNIQUE?
J 0
(-8465 4100);
DISPLAY 0.638298 (-8465 4100);
PAINT MONO (-8465 4100);
DISPLAY INVISIBLE (-8465 4100);
WIRE 16 -1 (-8300 3750)(-7525 3750);
WIRE 16 -1 (-5975 4050)(-6675 4050);
FORCEPROP 2 LAST SIG_NAME NC_PV09_RETIMER_CPU1_GL1_1
J 0
(-6585 4060);
DISPLAY 0.617021 (-6585 4060);
FORCEPROP 2 LASTPROP $XRERR UNIQUE?
J 0
(-5945 4050);
DISPLAY 0.638298 (-5945 4050);
PAINT MONO (-5945 4050);
DISPLAY INVISIBLE (-5945 4050);
WIRE 16 -1 (-5425 4250)(-5425 4350);
WIRE 16 -1 (-5000 4350)(-5425 4350);
WIRE 16 -1 (-6675 4350)(-5425 4350);
FORCEPROP 2 LAST SIG_NAME SW_P0V9_RETIMER_CPU1_SW1
J 0
(-6510 4360);
DISPLAY 0.617021 (-6510 4360);
FORCEPROP 2 LASTPROP $XRERR UNIQUE?
J 0
(-6750 4360);
DISPLAY 0.638298 (-6750 4360);
PAINT MONO (-6750 4360);
DISPLAY INVISIBLE (-6750 4360);
WIRE 16 -1 (-5850 1100)(-6550 1100);
FORCEPROP 2 LAST SIG_NAME NC_PV09_RETIMER_CPU1_GL2_2
J 0
(-6460 1110);
DISPLAY 0.617021 (-6460 1110);
FORCEPROP 2 LASTPROP $XRERR UNIQUE?
J 0
(-5820 1100);
DISPLAY 0.638298 (-5820 1100);
PAINT MONO (-5820 1100);
DISPLAY INVISIBLE (-5820 1100);
WIRE 16 -1 (-5850 1150)(-6550 1150);
FORCEPROP 2 LAST SIG_NAME NC_PV09_RETIMER_CPU1_GL1_2
J 0
(-6460 1160);
DISPLAY 0.617021 (-6460 1160);
FORCEPROP 2 LASTPROP $XRERR UNIQUE?
J 0
(-5820 1150);
DISPLAY 0.638298 (-5820 1150);
PAINT MONO (-5820 1150);
DISPLAY INVISIBLE (-5820 1150);
WIRE 16 -1 (-4875 1450)(-5400 1450);
WIRE 16 -1 (-5400 1350)(-5400 1450);
WIRE 16 -1 (-5400 1450)(-6550 1450);
FORCEPROP 2 LAST SIG_NAME SW_P0V9_RETIMER_CPU1_SW2
J 0
(-6385 1460);
DISPLAY 0.617021 (-6385 1460);
FORCEPROP 2 LASTPROP $XRERR UNIQUE?
J 0
(-6625 1460);
DISPLAY 0.638298 (-6625 1460);
PAINT MONO (-6625 1460);
DISPLAY INVISIBLE (-6625 1460);
WIRE 16 -1 (-5250 1800)(-4075 1800);
FORCEPROP 2 LAST SIG_NAME SW_P0V9_RETIMER_CPU1_BOOT2_RC
J 0
(-5010 1810);
DISPLAY 0.617021 (-5010 1810);
FORCEPROP 2 LASTPROP $XRERR UNIQUE?
J 0
(-5250 1810);
DISPLAY 0.638298 (-5250 1810);
PAINT MONO (-5250 1810);
DISPLAY INVISIBLE (-5250 1810);
WIRE 16 -1 (-6550 1800)(-5450 1800);
FORCEPROP 2 LAST SIG_NAME SW_P0V9_RETIMER_CPU1_BOOT2
J 0
(-6385 1810);
DISPLAY 0.617021 (-6385 1810);
FORCEPROP 2 LASTPROP $XRERR UNIQUE?
J 0
(-6625 1810);
DISPLAY 0.638298 (-6625 1810);
PAINT MONO (-6625 1810);
DISPLAY INVISIBLE (-6625 1810);
DOT 1 (-2475 1075);
DOT 1 (-2225 1075);
DOT 1 (-7625 4700);
DOT 1 (-2800 1075);
DOT 1 (-3225 1075);
DOT 1 (-6350 5000);
DOT 1 (-950 5325);
DOT 1 (-2775 5325);
DOT 1 (-3450 1075);
DOT 1 (-4000 1450);
DOT 1 (-5400 1450);
DOT 1 (-6375 950);
DOT 1 (-2600 3975);
DOT 1 (-3575 4350);
DOT 1 (-3350 4350);
DOT 1 (-3575 3975);
DOT 1 (-3800 3975);
DOT 1 (-4975 5325);
DOT 1 (-2000 4350);
DOT 1 (-3675 1075);
DOT 1 (-3350 3975);
DOT 1 (-3125 3975);
DOT 1 (-3800 4350);
DOT 1 (-4350 4350);
DOT 1 (-8350 5500);
DOT 1 (-8175 5500);
DOT 1 (-8100 1350);
DOT 1 (-8750 2050);
DOT 1 (-8750 2600);
DOT 1 (-7500 1800);
DOT 1 (-6375 850);
DOT 1 (-6375 900);
DOT 1 (-6225 2100);
DOT 1 (-5350 2425);
DOT 1 (-4350 2425);
DOT 1 (-3675 1450);
DOT 1 (-3450 1450);
DOT 1 (-3225 1450);
DOT 1 (-3875 2425);
DOT 1 (-3500 2425);
DOT 1 (-3100 2425);
DOT 1 (-8225 4250);
DOT 1 (-8875 4950);
DOT 1 (-8875 5500);
DOT 1 (-8875 5900);
DOT 1 (-6500 3850);
DOT 1 (-5975 5325);
DOT 1 (-4125 4350);
DOT 1 (-3125 4350);
DOT 1 (-4475 5325);
DOT 1 (-3625 5325);
DOT 1 (-2650 2425);
DOT 1 (-2300 2425);
DOT 1 (-2925 3975);
DOT 1 (-2000 3975);
DOT 1 (-2425 5325);
DOT 1 (-6500 3800);
DOT 1 (-8050 2600);
DOT 1 (-4850 2425);
DOT 1 (-5425 4350);
DOT 1 (-5850 2425);
DOT 1 (-4250 1450);
DOT 1 (-3000 1075);
DOT 1 (-6500 3750);
DOT 1 (-2925 4350);
DOT 1 (-2600 4350);
DOT 1 (-2325 4350);
DOT 1 (-2325 3975);
DOT 1 (-2475 1450);
DOT 1 (-2225 1450);
DOT 1 (-5475 5325);
DOT 1 (-4000 5325);
DOT 1 (-3225 5325);
DOT 1 (-2375 5325);
DOT 1 (-2800 1450);
DOT 1 (-3000 1450);
FORCENOTE
P0V9_CPU1_RT_2D_PHASE2
(-7700 2775) 0;
DISPLAY LEFT (-7700 2775);
DISPLAY 1.595745 (-7700 2775);
PAINT WHITE (-7700 2775);
FORCENOTE
PGL6312.121AHLT
(-5000 1225) 0;
DISPLAY LEFT (-5000 1225);
DISPLAY 0.808511 (-5000 1225);
PAINT PINK (-5000 1225);
FORCENOTE
ESR=27M OHM
(-2300 4852) 0;
DISPLAY LEFT (-2300 4852);
DISPLAY 0.808511 (-2300 4852);
PAINT PINK (-2300 4852);
FORCENOTE
HCBS4545-101
(-1950 5215) 0;
DISPLAY LEFT (-1950 5215);
DISPLAY 1.021277 (-1950 5215);
PAINT PINK (-1950 5215);
FORCENOTE
6.5*6.5*10
(-4975 1150) 0;
DISPLAY LEFT (-4975 1150);
DISPLAY 0.808511 (-4975 1150);
PAINT PINK (-4975 1150);
FORCENOTE
ISAT=60 @100C
(-5000 1275) 0;
DISPLAY LEFT (-5000 1275);
DISPLAY 0.808511 (-5000 1275);
PAINT PINK (-5000 1275);
FORCENOTE
5*5.8
(-2175 1850) 0;
DISPLAY LEFT (-2175 1850);
DISPLAY 0.808511 (-2175 1850);
PAINT PINK (-2175 1850);
FORCENOTE
RI=3A
(-2175 1900) 0;
DISPLAY LEFT (-2175 1900);
DISPLAY 0.808511 (-2175 1900);
PAINT PINK (-2175 1900);
FORCENOTE
ESR=27M OHM
(-2175 1952) 0;
DISPLAY LEFT (-2175 1952);
DISPLAY 0.808511 (-2175 1952);
PAINT PINK (-2175 1952);
FORCENOTE
DCR=0.17MOHM
(-5000 1325) 0;
DISPLAY LEFT (-5000 1325);
DISPLAY 0.808511 (-5000 1325);
PAINT PINK (-5000 1325);
FORCENOTE
5*5.8
(-2300 4750) 0;
DISPLAY LEFT (-2300 4750);
DISPLAY 0.808511 (-2300 4750);
PAINT PINK (-2300 4750);
FORCENOTE
PGL6312.121AHLT
(-5125 4125) 0;
DISPLAY LEFT (-5125 4125);
DISPLAY 0.808511 (-5125 4125);
PAINT PINK (-5125 4125);
FORCENOTE
RI=3A
(-2300 4800) 0;
DISPLAY LEFT (-2300 4800);
DISPLAY 0.808511 (-2300 4800);
PAINT PINK (-2300 4800);
FORCENOTE
4.5*4.5*4.5
(-1950 5150) 0;
DISPLAY LEFT (-1950 5150);
DISPLAY 1.021277 (-1950 5150);
PAINT PINK (-1950 5150);
FORCENOTE
ISAT = 13A @ 100C
(-1950 5050) 0;
DISPLAY LEFT (-1950 5050);
DISPLAY 1.021277 (-1950 5050);
PAINT PINK (-1950 5050);
FORCENOTE
6.5*6.5*10
(-5100 4050) 0;
DISPLAY LEFT (-5100 4050);
DISPLAY 0.808511 (-5100 4050);
PAINT PINK (-5100 4050);
FORCENOTE
DCR = 0.105M OHM
(-1950 4975) 0;
DISPLAY LEFT (-1950 4975);
DISPLAY 1.021277 (-1950 4975);
PAINT PINK (-1950 4975);
FORCENOTE
P0V9_CPU1_RT_2D_PHASE1
(-7825 5800) 0;
DISPLAY LEFT (-7825 5800);
DISPLAY 1.595745 (-7825 5800);
PAINT WHITE (-7825 5800);
FORCENOTE
MAIN SOURCE: RENESAS    BOM
(-3400 6575) 0;
DISPLAY LEFT (-3400 6575);
DISPLAY 1.021277 (-3400 6575);
PAINT WHITE (-3400 6575);
FORCENOTE
BOM NOTE
(-4425 6500) 0;
DISPLAY LEFT (-4425 6500);
DISPLAY 1.021277 (-4425 6500);
PAINT WHITE (-4425 6500);
FORCENOTE
PU6511,PU6512 = AL099390004 / ISL99390FRZ-TR5935
(-3400 6500) 0;
DISPLAY LEFT (-3400 6500);
DISPLAY 1.021277 (-3400 6500);
PAINT WHITE (-3400 6500);
FORCENOTE
PC6611_1,PC6646 = EMPTY
(-3400 6000) 0;
DISPLAY LEFT (-3400 6000);
DISPLAY 1.021277 (-3400 6000);
PAINT WHITE (-3400 6000);
FORCENOTE
PC6621,PC6640 = CH4224K1B01
(-3400 6075) 0;
DISPLAY LEFT (-3400 6075);
DISPLAY 1.021277 (-3400 6075);
PAINT WHITE (-3400 6075);
FORCENOTE
PR6626,PR6631,PR6625 = EMPTY
(-3400 6150) 0;
DISPLAY LEFT (-3400 6150);
DISPLAY 1.021277 (-3400 6150);
PAINT WHITE (-3400 6150);
FORCENOTE
PR6623,PR6629,PR6622,PR6628 = CS00002JB13
(-3400 6225) 0;
DISPLAY LEFT (-3400 6225);
DISPLAY 1.021277 (-3400 6225);
PAINT WHITE (-3400 6225);
FORCENOTE
PU6511,PU6512 = AL021590000 / TDA21590
(-3400 6300) 0;
DISPLAY LEFT (-3400 6300);
DISPLAY 1.021277 (-3400 6300);
PAINT WHITE (-3400 6300);
FORCENOTE
2ND SOURCE: INFENEON   BOM
(-3400 6375) 0;
DISPLAY LEFT (-3400 6375);
DISPLAY 1.021277 (-3400 6375);
PAINT WHITE (-3400 6375);
FORCENOTE
DCR=0.17MOHM
(-5125 4225) 0;
DISPLAY LEFT (-5125 4225);
DISPLAY 0.808511 (-5125 4225);
PAINT PINK (-5125 4225);
FORCENOTE
ISAT=60 @100C
(-5125 4175) 0;
DISPLAY LEFT (-5125 4175);
DISPLAY 0.808511 (-5125 4175);
PAINT PINK (-5125 4175);
QUIT
